FILE_TYPE = MACRO_DRAWING;
SET COLOR_WIRE YELLOW;
SET COLOR_PROP ORANGE;
SET COLOR_DOT WHITE;
SET COLOR_ARC YELLOW;
SET COLOR_BODY GREEN;
SET COLOR_NOTE PURPLE;
SET PROP_DISPLAY VALUE;
SET PAGE_NUMBER P26;
FORCEADD OFFPAGE..2
R 2
(-1225 25);
FORCEPROP 2 LAST $XR1 95 
J 0
(-1569 25);
DISPLAY 0.638298 (-1569 25);
PAINT MONO (-1569 25);
FORCEPROP 2 LAST $XR0 94 
J 0
(-1479 25);
DISPLAY 0.638298 (-1479 25);
PAINT MONO (-1479 25);
FORCEPROP 2 LAST CDS_LIB standard
J 0
(-1225 25);
PAINT MONO (-1225 25);
DISPLAY INVISIBLE (-1225 25);
FORCEPROP 1 LAST OFFPAGE TRUE
J 2
(-1550 -100);
DISPLAY 0.872340 (-1550 -100);
DISPLAY INVISIBLE (-1550 -100);
FORCEPROP 1 LAST COMMENT_BODY TRUE
J 2
(-1180 -70);
DISPLAY 0.872340 (-1180 -70);
PAINT GREEN (-1180 -70);
DISPLAY INVISIBLE (-1180 -70);
FORCEPROP 2 LAST PATH I1
J 0
(-1175 100);
DISPLAY 1.021277 (-1175 100);
DISPLAY INVISIBLE (-1175 100);
FORCEADD OFFPAGE..3
R 2
(-1225 475);
FORCEPROP 2 LAST $XR1 95 
J 0
(-1594 475);
DISPLAY 0.638298 (-1594 475);
PAINT MONO (-1594 475);
FORCEPROP 2 LAST $XR0 94 
J 0
(-1504 475);
DISPLAY 0.638298 (-1504 475);
PAINT MONO (-1504 475);
FORCEPROP 2 LAST CDS_LIB standard
J 0
(-1225 475);
DISPLAY INVISIBLE (-1225 475);
FORCEPROP 1 LAST OFFPAGE TRUE
J 2
(-1550 350);
DISPLAY 0.872340 (-1550 350);
DISPLAY INVISIBLE (-1550 350);
FORCEPROP 1 LAST COMMENT_BODY TRUE
J 2
(-1175 375);
DISPLAY 0.872340 (-1175 375);
PAINT GREEN (-1175 375);
DISPLAY INVISIBLE (-1175 375);
FORCEPROP 2 LAST PATH I10
J 0
(-1175 550);
DISPLAY 1.021277 (-1175 550);
DISPLAY INVISIBLE (-1175 550);
FORCEADD TAP..1
(3225 400);
FORCEPROP 3 LASTPIN (3175 400) SIG_NAME M_G_CPU0_SB_CS_N<2>
J 0
(3185 410);
DISPLAY 0.659574 (3185 410);
PAINT MONO (3185 410);
DISPLAY INVISIBLE (3185 410);
FORCEPROP 1 LASTPIN (3175 400) BN 2
J 0
(3163 408);
DISPLAY 0.680851 (3163 408);
PAINT GREEN (3163 408);
FORCEPROP 2 LAST CDS_LIB standard
J 0
(3225 400);
DISPLAY INVISIBLE (3225 400);
FORCEPROP 1 LAST BODY_TYPE PLUMBING
J 0
(3225 450);
DISPLAY 0.872340 (3225 450);
PAINT GREEN (3225 450);
DISPLAY INVISIBLE (3225 450);
FORCEPROP 1 LAST HDL_TAP TRUE
J 0
(3550 275);
DISPLAY 0.872340 (3550 275);
DISPLAY INVISIBLE (3550 275);
FORCEPROP 1 LAST PATH I100
J 0
(3223 400);
DISPLAY 0.872340 (3223 400);
PAINT GREEN (3223 400);
DISPLAY INVISIBLE (3223 400);
FORCEADD TAP..1
(3225 650);
FORCEPROP 3 LASTPIN (3175 650) SIG_NAME M_G_CPU0_SA_CS_N<1>
J 0
(3185 660);
DISPLAY 0.659574 (3185 660);
PAINT MONO (3185 660);
DISPLAY INVISIBLE (3185 660);
FORCEPROP 1 LASTPIN (3175 650) BN 1
J 0
(3163 658);
DISPLAY 0.680851 (3163 658);
PAINT GREEN (3163 658);
FORCEPROP 2 LAST CDS_LIB standard
J 0
(3225 650);
DISPLAY INVISIBLE (3225 650);
FORCEPROP 1 LAST BODY_TYPE PLUMBING
J 0
(3225 700);
DISPLAY 0.872340 (3225 700);
PAINT GREEN (3225 700);
DISPLAY INVISIBLE (3225 700);
FORCEPROP 1 LAST HDL_TAP TRUE
J 0
(3550 525);
DISPLAY 0.872340 (3550 525);
DISPLAY INVISIBLE (3550 525);
FORCEPROP 1 LAST PATH I101
J 0
(3223 650);
DISPLAY 0.872340 (3223 650);
PAINT GREEN (3223 650);
DISPLAY INVISIBLE (3223 650);
FORCEADD TAP..1
(3225 700);
FORCEPROP 3 LASTPIN (3175 700) SIG_NAME M_G_CPU0_SA_CS_N<2>
J 0
(3185 710);
DISPLAY 0.659574 (3185 710);
PAINT MONO (3185 710);
DISPLAY INVISIBLE (3185 710);
FORCEPROP 1 LASTPIN (3175 700) BN 2
J 0
(3163 708);
DISPLAY 0.680851 (3163 708);
PAINT GREEN (3163 708);
FORCEPROP 2 LAST CDS_LIB standard
J 0
(3225 700);
DISPLAY INVISIBLE (3225 700);
FORCEPROP 1 LAST BODY_TYPE PLUMBING
J 0
(3225 750);
DISPLAY 0.872340 (3225 750);
PAINT GREEN (3225 750);
DISPLAY INVISIBLE (3225 750);
FORCEPROP 1 LAST HDL_TAP TRUE
J 0
(3550 575);
DISPLAY 0.872340 (3550 575);
DISPLAY INVISIBLE (3550 575);
FORCEPROP 1 LAST PATH I102
J 0
(3223 700);
DISPLAY 0.872340 (3223 700);
PAINT GREEN (3223 700);
DISPLAY INVISIBLE (3223 700);
FORCEADD TAP..1
(3225 600);
FORCEPROP 3 LASTPIN (3175 600) SIG_NAME M_G_CPU0_SA_CS_N<0>
J 0
(3185 610);
DISPLAY 0.659574 (3185 610);
PAINT MONO (3185 610);
DISPLAY INVISIBLE (3185 610);
FORCEPROP 1 LASTPIN (3175 600) BN 0
J 0
(3163 608);
DISPLAY 0.680851 (3163 608);
PAINT GREEN (3163 608);
FORCEPROP 2 LAST CDS_LIB standard
J 0
(3225 600);
DISPLAY INVISIBLE (3225 600);
FORCEPROP 1 LAST BODY_TYPE PLUMBING
J 0
(3225 650);
DISPLAY 0.872340 (3225 650);
PAINT GREEN (3225 650);
DISPLAY INVISIBLE (3225 650);
FORCEPROP 1 LAST HDL_TAP TRUE
J 0
(3550 475);
DISPLAY 0.872340 (3550 475);
DISPLAY INVISIBLE (3550 475);
FORCEPROP 1 LAST PATH I103
J 0
(3223 600);
DISPLAY 0.872340 (3223 600);
PAINT GREEN (3223 600);
DISPLAY INVISIBLE (3223 600);
FORCEADD TAP..1
(3225 750);
FORCEPROP 3 LASTPIN (3175 750) SIG_NAME M_G_CPU0_SA_CS_N<3>
J 0
(3185 760);
DISPLAY 0.659574 (3185 760);
PAINT MONO (3185 760);
DISPLAY INVISIBLE (3185 760);
FORCEPROP 1 LASTPIN (3175 750) BN 3
J 0
(3163 758);
DISPLAY 0.680851 (3163 758);
PAINT GREEN (3163 758);
FORCEPROP 2 LAST CDS_LIB standard
J 0
(3225 750);
DISPLAY INVISIBLE (3225 750);
FORCEPROP 1 LAST BODY_TYPE PLUMBING
J 0
(3225 800);
DISPLAY 0.872340 (3225 800);
PAINT GREEN (3225 800);
DISPLAY INVISIBLE (3225 800);
FORCEPROP 1 LAST HDL_TAP TRUE
J 0
(3550 625);
DISPLAY 0.872340 (3550 625);
DISPLAY INVISIBLE (3550 625);
FORCEPROP 1 LAST PATH I104
J 0
(3223 750);
DISPLAY 0.872340 (3223 750);
PAINT GREEN (3223 750);
DISPLAY INVISIBLE (3223 750);
FORCEADD TAP..1
(3225 950);
FORCEPROP 3 LASTPIN (3175 950) SIG_NAME M_G_CPU0_SB_CA<0>
J 0
(3185 960);
DISPLAY 0.659574 (3185 960);
PAINT MONO (3185 960);
DISPLAY INVISIBLE (3185 960);
FORCEPROP 1 LASTPIN (3175 950) BN 0
J 0
(3163 958);
DISPLAY 0.680851 (3163 958);
PAINT GREEN (3163 958);
FORCEPROP 2 LAST CDS_LIB standard
J 0
(3225 950);
DISPLAY INVISIBLE (3225 950);
FORCEPROP 1 LAST BODY_TYPE PLUMBING
J 0
(3225 1000);
DISPLAY 0.872340 (3225 1000);
PAINT GREEN (3225 1000);
DISPLAY INVISIBLE (3225 1000);
FORCEPROP 1 LAST HDL_TAP TRUE
J 0
(3550 825);
DISPLAY 0.872340 (3550 825);
DISPLAY INVISIBLE (3550 825);
FORCEPROP 1 LAST PATH I105
J 0
(3223 950);
DISPLAY 0.872340 (3223 950);
PAINT GREEN (3223 950);
DISPLAY INVISIBLE (3223 950);
FORCEADD TAP..1
(3225 1050);
FORCEPROP 3 LASTPIN (3175 1050) SIG_NAME M_G_CPU0_SB_CA<2>
J 0
(3185 1060);
DISPLAY 0.659574 (3185 1060);
PAINT MONO (3185 1060);
DISPLAY INVISIBLE (3185 1060);
FORCEPROP 1 LASTPIN (3175 1050) BN 2
J 0
(3163 1058);
DISPLAY 0.680851 (3163 1058);
PAINT GREEN (3163 1058);
FORCEPROP 2 LAST CDS_LIB standard
J 0
(3225 1050);
DISPLAY INVISIBLE (3225 1050);
FORCEPROP 1 LAST BODY_TYPE PLUMBING
J 0
(3225 1100);
DISPLAY 0.872340 (3225 1100);
PAINT GREEN (3225 1100);
DISPLAY INVISIBLE (3225 1100);
FORCEPROP 1 LAST HDL_TAP TRUE
J 0
(3550 925);
DISPLAY 0.872340 (3550 925);
DISPLAY INVISIBLE (3550 925);
FORCEPROP 1 LAST PATH I106
J 0
(3223 1050);
DISPLAY 0.872340 (3223 1050);
PAINT GREEN (3223 1050);
DISPLAY INVISIBLE (3223 1050);
FORCEADD TAP..1
(3225 1000);
FORCEPROP 3 LASTPIN (3175 1000) SIG_NAME M_G_CPU0_SB_CA<1>
J 0
(3185 1010);
DISPLAY 0.659574 (3185 1010);
PAINT MONO (3185 1010);
DISPLAY INVISIBLE (3185 1010);
FORCEPROP 1 LASTPIN (3175 1000) BN 1
J 0
(3163 1008);
DISPLAY 0.680851 (3163 1008);
PAINT GREEN (3163 1008);
FORCEPROP 2 LAST CDS_LIB standard
J 0
(3225 1000);
DISPLAY INVISIBLE (3225 1000);
FORCEPROP 1 LAST BODY_TYPE PLUMBING
J 0
(3225 1050);
DISPLAY 0.872340 (3225 1050);
PAINT GREEN (3225 1050);
DISPLAY INVISIBLE (3225 1050);
FORCEPROP 1 LAST HDL_TAP TRUE
J 0
(3550 875);
DISPLAY 0.872340 (3550 875);
DISPLAY INVISIBLE (3550 875);
FORCEPROP 1 LAST PATH I107
J 0
(3223 1000);
DISPLAY 0.872340 (3223 1000);
PAINT GREEN (3223 1000);
DISPLAY INVISIBLE (3223 1000);
FORCEADD TAP..1
(3225 1200);
FORCEPROP 3 LASTPIN (3175 1200) SIG_NAME M_G_CPU0_SB_CA<5>
J 0
(3185 1210);
DISPLAY 0.659574 (3185 1210);
PAINT MONO (3185 1210);
DISPLAY INVISIBLE (3185 1210);
FORCEPROP 1 LASTPIN (3175 1200) BN 5
J 0
(3163 1208);
DISPLAY 0.680851 (3163 1208);
PAINT GREEN (3163 1208);
FORCEPROP 2 LAST CDS_LIB standard
J 0
(3225 1200);
DISPLAY INVISIBLE (3225 1200);
FORCEPROP 1 LAST BODY_TYPE PLUMBING
J 0
(3225 1250);
DISPLAY 0.872340 (3225 1250);
PAINT GREEN (3225 1250);
DISPLAY INVISIBLE (3225 1250);
FORCEPROP 1 LAST HDL_TAP TRUE
J 0
(3550 1075);
DISPLAY 0.872340 (3550 1075);
DISPLAY INVISIBLE (3550 1075);
FORCEPROP 1 LAST PATH I108
J 0
(3223 1200);
DISPLAY 0.872340 (3223 1200);
PAINT GREEN (3223 1200);
DISPLAY INVISIBLE (3223 1200);
FORCEADD TAP..1
(3225 1100);
FORCEPROP 3 LASTPIN (3175 1100) SIG_NAME M_G_CPU0_SB_CA<3>
J 0
(3185 1110);
DISPLAY 0.659574 (3185 1110);
PAINT MONO (3185 1110);
DISPLAY INVISIBLE (3185 1110);
FORCEPROP 1 LASTPIN (3175 1100) BN 3
J 0
(3163 1108);
DISPLAY 0.680851 (3163 1108);
PAINT GREEN (3163 1108);
FORCEPROP 2 LAST CDS_LIB standard
J 0
(3225 1100);
DISPLAY INVISIBLE (3225 1100);
FORCEPROP 1 LAST BODY_TYPE PLUMBING
J 0
(3225 1150);
DISPLAY 0.872340 (3225 1150);
PAINT GREEN (3225 1150);
DISPLAY INVISIBLE (3225 1150);
FORCEPROP 1 LAST HDL_TAP TRUE
J 0
(3550 975);
DISPLAY 0.872340 (3550 975);
DISPLAY INVISIBLE (3550 975);
FORCEPROP 1 LAST PATH I109
J 0
(3223 1100);
DISPLAY 0.872340 (3223 1100);
PAINT GREEN (3223 1100);
DISPLAY INVISIBLE (3223 1100);
FORCEADD OFFPAGE..3
R 2
(-1225 2075);
FORCEPROP 2 LAST $XR1 95 
J 0
(-1594 2075);
DISPLAY 0.638298 (-1594 2075);
PAINT MONO (-1594 2075);
FORCEPROP 2 LAST $XR0 94 
J 0
(-1504 2075);
DISPLAY 0.638298 (-1504 2075);
PAINT MONO (-1504 2075);
FORCEPROP 2 LAST CDS_LIB standard
J 0
(-1225 2075);
DISPLAY INVISIBLE (-1225 2075);
FORCEPROP 1 LAST OFFPAGE TRUE
J 2
(-1550 1950);
DISPLAY 0.872340 (-1550 1950);
DISPLAY INVISIBLE (-1550 1950);
FORCEPROP 1 LAST COMMENT_BODY TRUE
J 2
(-1175 1975);
DISPLAY 0.872340 (-1175 1975);
PAINT GREEN (-1175 1975);
DISPLAY INVISIBLE (-1175 1975);
FORCEPROP 2 LAST PATH I11
J 0
(-1175 2150);
DISPLAY 1.021277 (-1175 2150);
DISPLAY INVISIBLE (-1175 2150);
FORCEADD TAP..1
(3225 1150);
FORCEPROP 3 LASTPIN (3175 1150) SIG_NAME M_G_CPU0_SB_CA<4>
J 0
(3185 1160);
DISPLAY 0.659574 (3185 1160);
PAINT MONO (3185 1160);
DISPLAY INVISIBLE (3185 1160);
FORCEPROP 1 LASTPIN (3175 1150) BN 4
J 0
(3163 1158);
DISPLAY 0.680851 (3163 1158);
PAINT GREEN (3163 1158);
FORCEPROP 2 LAST CDS_LIB standard
J 0
(3225 1150);
DISPLAY INVISIBLE (3225 1150);
FORCEPROP 1 LAST BODY_TYPE PLUMBING
J 0
(3225 1200);
DISPLAY 0.872340 (3225 1200);
PAINT GREEN (3225 1200);
DISPLAY INVISIBLE (3225 1200);
FORCEPROP 1 LAST HDL_TAP TRUE
J 0
(3550 1025);
DISPLAY 0.872340 (3550 1025);
DISPLAY INVISIBLE (3550 1025);
FORCEPROP 1 LAST PATH I110
J 0
(3223 1150);
DISPLAY 0.872340 (3223 1150);
PAINT GREEN (3223 1150);
DISPLAY INVISIBLE (3223 1150);
FORCEADD TAP..1
(3225 1250);
FORCEPROP 3 LASTPIN (3175 1250) SIG_NAME M_G_CPU0_SB_CA<6>
J 0
(3185 1260);
DISPLAY 0.659574 (3185 1260);
PAINT MONO (3185 1260);
DISPLAY INVISIBLE (3185 1260);
FORCEPROP 1 LASTPIN (3175 1250) BN 6
J 0
(3163 1258);
DISPLAY 0.680851 (3163 1258);
PAINT GREEN (3163 1258);
FORCEPROP 2 LAST CDS_LIB standard
J 0
(3225 1250);
DISPLAY INVISIBLE (3225 1250);
FORCEPROP 1 LAST BODY_TYPE PLUMBING
J 0
(3225 1300);
DISPLAY 0.872340 (3225 1300);
PAINT GREEN (3225 1300);
DISPLAY INVISIBLE (3225 1300);
FORCEPROP 1 LAST HDL_TAP TRUE
J 0
(3550 1125);
DISPLAY 0.872340 (3550 1125);
DISPLAY INVISIBLE (3550 1125);
FORCEPROP 1 LAST PATH I111
J 0
(3223 1250);
DISPLAY 0.872340 (3223 1250);
PAINT GREEN (3223 1250);
DISPLAY INVISIBLE (3223 1250);
FORCEADD TAP..1
(3225 1450);
FORCEPROP 3 LASTPIN (3175 1450) SIG_NAME M_G_CPU0_SA_CA<0>
J 0
(3185 1460);
DISPLAY 0.659574 (3185 1460);
PAINT MONO (3185 1460);
DISPLAY INVISIBLE (3185 1460);
FORCEPROP 1 LASTPIN (3175 1450) BN 0
J 0
(3163 1458);
DISPLAY 0.680851 (3163 1458);
PAINT GREEN (3163 1458);
FORCEPROP 2 LAST CDS_LIB standard
J 0
(3225 1450);
DISPLAY INVISIBLE (3225 1450);
FORCEPROP 1 LAST BODY_TYPE PLUMBING
J 0
(3225 1500);
DISPLAY 0.872340 (3225 1500);
PAINT GREEN (3225 1500);
DISPLAY INVISIBLE (3225 1500);
FORCEPROP 1 LAST HDL_TAP TRUE
J 0
(3550 1325);
DISPLAY 0.872340 (3550 1325);
DISPLAY INVISIBLE (3550 1325);
FORCEPROP 1 LAST PATH I112
J 0
(3223 1450);
DISPLAY 0.872340 (3223 1450);
PAINT GREEN (3223 1450);
DISPLAY INVISIBLE (3223 1450);
FORCEADD TAP..1
(3225 1550);
FORCEPROP 3 LASTPIN (3175 1550) SIG_NAME M_G_CPU0_SA_CA<2>
J 0
(3185 1560);
DISPLAY 0.659574 (3185 1560);
PAINT MONO (3185 1560);
DISPLAY INVISIBLE (3185 1560);
FORCEPROP 1 LASTPIN (3175 1550) BN 2
J 0
(3163 1558);
DISPLAY 0.680851 (3163 1558);
PAINT GREEN (3163 1558);
FORCEPROP 2 LAST CDS_LIB standard
J 0
(3225 1550);
DISPLAY INVISIBLE (3225 1550);
FORCEPROP 1 LAST BODY_TYPE PLUMBING
J 0
(3225 1600);
DISPLAY 0.872340 (3225 1600);
PAINT GREEN (3225 1600);
DISPLAY INVISIBLE (3225 1600);
FORCEPROP 1 LAST HDL_TAP TRUE
J 0
(3550 1425);
DISPLAY 0.872340 (3550 1425);
DISPLAY INVISIBLE (3550 1425);
FORCEPROP 1 LAST PATH I113
J 0
(3223 1550);
DISPLAY 0.872340 (3223 1550);
PAINT GREEN (3223 1550);
DISPLAY INVISIBLE (3223 1550);
FORCEADD TAP..1
(3225 1500);
FORCEPROP 3 LASTPIN (3175 1500) SIG_NAME M_G_CPU0_SA_CA<1>
J 0
(3185 1510);
DISPLAY 0.659574 (3185 1510);
PAINT MONO (3185 1510);
DISPLAY INVISIBLE (3185 1510);
FORCEPROP 1 LASTPIN (3175 1500) BN 1
J 0
(3163 1508);
DISPLAY 0.680851 (3163 1508);
PAINT GREEN (3163 1508);
FORCEPROP 2 LAST CDS_LIB standard
J 0
(3225 1500);
DISPLAY INVISIBLE (3225 1500);
FORCEPROP 1 LAST BODY_TYPE PLUMBING
J 0
(3225 1550);
DISPLAY 0.872340 (3225 1550);
PAINT GREEN (3225 1550);
DISPLAY INVISIBLE (3225 1550);
FORCEPROP 1 LAST HDL_TAP TRUE
J 0
(3550 1375);
DISPLAY 0.872340 (3550 1375);
DISPLAY INVISIBLE (3550 1375);
FORCEPROP 1 LAST PATH I114
J 0
(3223 1500);
DISPLAY 0.872340 (3223 1500);
PAINT GREEN (3223 1500);
DISPLAY INVISIBLE (3223 1500);
FORCEADD TAP..1
(3225 1600);
FORCEPROP 3 LASTPIN (3175 1600) SIG_NAME M_G_CPU0_SA_CA<3>
J 0
(3185 1610);
DISPLAY 0.659574 (3185 1610);
PAINT MONO (3185 1610);
DISPLAY INVISIBLE (3185 1610);
FORCEPROP 1 LASTPIN (3175 1600) BN 3
J 0
(3163 1608);
DISPLAY 0.680851 (3163 1608);
PAINT GREEN (3163 1608);
FORCEPROP 2 LAST CDS_LIB standard
J 0
(3225 1600);
DISPLAY INVISIBLE (3225 1600);
FORCEPROP 1 LAST BODY_TYPE PLUMBING
J 0
(3225 1650);
DISPLAY 0.872340 (3225 1650);
PAINT GREEN (3225 1650);
DISPLAY INVISIBLE (3225 1650);
FORCEPROP 1 LAST HDL_TAP TRUE
J 0
(3550 1475);
DISPLAY 0.872340 (3550 1475);
DISPLAY INVISIBLE (3550 1475);
FORCEPROP 1 LAST PATH I115
J 0
(3223 1600);
DISPLAY 0.872340 (3223 1600);
PAINT GREEN (3223 1600);
DISPLAY INVISIBLE (3223 1600);
FORCEADD TAP..1
(3225 1700);
FORCEPROP 3 LASTPIN (3175 1700) SIG_NAME M_G_CPU0_SA_CA<5>
J 0
(3185 1710);
DISPLAY 0.659574 (3185 1710);
PAINT MONO (3185 1710);
DISPLAY INVISIBLE (3185 1710);
FORCEPROP 1 LASTPIN (3175 1700) BN 5
J 0
(3163 1708);
DISPLAY 0.680851 (3163 1708);
PAINT GREEN (3163 1708);
FORCEPROP 2 LAST CDS_LIB standard
J 0
(3225 1700);
DISPLAY INVISIBLE (3225 1700);
FORCEPROP 1 LAST BODY_TYPE PLUMBING
J 0
(3225 1750);
DISPLAY 0.872340 (3225 1750);
PAINT GREEN (3225 1750);
DISPLAY INVISIBLE (3225 1750);
FORCEPROP 1 LAST HDL_TAP TRUE
J 0
(3550 1575);
DISPLAY 0.872340 (3550 1575);
DISPLAY INVISIBLE (3550 1575);
FORCEPROP 1 LAST PATH I116
J 0
(3223 1700);
DISPLAY 0.872340 (3223 1700);
PAINT GREEN (3223 1700);
DISPLAY INVISIBLE (3223 1700);
FORCEADD TAP..1
(3225 1650);
FORCEPROP 3 LASTPIN (3175 1650) SIG_NAME M_G_CPU0_SA_CA<4>
J 0
(3185 1660);
DISPLAY 0.659574 (3185 1660);
PAINT MONO (3185 1660);
DISPLAY INVISIBLE (3185 1660);
FORCEPROP 1 LASTPIN (3175 1650) BN 4
J 0
(3163 1658);
DISPLAY 0.680851 (3163 1658);
PAINT GREEN (3163 1658);
FORCEPROP 2 LAST CDS_LIB standard
J 0
(3225 1650);
DISPLAY INVISIBLE (3225 1650);
FORCEPROP 1 LAST BODY_TYPE PLUMBING
J 0
(3225 1700);
DISPLAY 0.872340 (3225 1700);
PAINT GREEN (3225 1700);
DISPLAY INVISIBLE (3225 1700);
FORCEPROP 1 LAST HDL_TAP TRUE
J 0
(3550 1525);
DISPLAY 0.872340 (3550 1525);
DISPLAY INVISIBLE (3550 1525);
FORCEPROP 1 LAST PATH I117
J 0
(3223 1650);
DISPLAY 0.872340 (3223 1650);
PAINT GREEN (3223 1650);
DISPLAY INVISIBLE (3223 1650);
FORCEADD TAP..1
(3225 1750);
FORCEPROP 3 LASTPIN (3175 1750) SIG_NAME M_G_CPU0_SA_CA<6>
J 0
(3185 1760);
DISPLAY 0.659574 (3185 1760);
PAINT MONO (3185 1760);
DISPLAY INVISIBLE (3185 1760);
FORCEPROP 1 LASTPIN (3175 1750) BN 6
J 0
(3163 1758);
DISPLAY 0.680851 (3163 1758);
PAINT GREEN (3163 1758);
FORCEPROP 2 LAST CDS_LIB standard
J 0
(3225 1750);
DISPLAY INVISIBLE (3225 1750);
FORCEPROP 1 LAST BODY_TYPE PLUMBING
J 0
(3225 1800);
DISPLAY 0.872340 (3225 1800);
PAINT GREEN (3225 1800);
DISPLAY INVISIBLE (3225 1800);
FORCEPROP 1 LAST HDL_TAP TRUE
J 0
(3550 1625);
DISPLAY 0.872340 (3550 1625);
DISPLAY INVISIBLE (3550 1625);
FORCEPROP 1 LAST PATH I118
J 0
(3223 1750);
DISPLAY 0.872340 (3223 1750);
PAINT GREEN (3223 1750);
DISPLAY INVISIBLE (3223 1750);
FORCEADD TAP..1
(3225 1900);
FORCEPROP 3 LASTPIN (3175 1900) SIG_NAME M_G_CPU0_SB_DQS_DN<0>
J 0
(3185 1910);
DISPLAY 0.659574 (3185 1910);
PAINT MONO (3185 1910);
DISPLAY INVISIBLE (3185 1910);
FORCEPROP 1 LASTPIN (3175 1900) BN 0
J 0
(3163 1908);
DISPLAY 0.680851 (3163 1908);
PAINT GREEN (3163 1908);
FORCEPROP 2 LAST CDS_LIB standard
J 0
(3225 1900);
DISPLAY INVISIBLE (3225 1900);
FORCEPROP 1 LAST BODY_TYPE PLUMBING
J 0
(3225 1950);
DISPLAY 0.872340 (3225 1950);
PAINT GREEN (3225 1950);
DISPLAY INVISIBLE (3225 1950);
FORCEPROP 1 LAST HDL_TAP TRUE
J 0
(3550 1775);
DISPLAY 0.872340 (3550 1775);
DISPLAY INVISIBLE (3550 1775);
FORCEPROP 1 LAST PATH I119
J 0
(3223 1900);
DISPLAY 0.872340 (3223 1900);
PAINT GREEN (3223 1900);
DISPLAY INVISIBLE (3223 1900);
FORCEADD TAP..1
R 2
(-200 300);
FORCEPROP 3 LASTPIN (-150 300) SIG_NAME M_G_CPU0_SB_CB<4>
J 0
(-140 310);
DISPLAY 0.659574 (-140 310);
PAINT MONO (-140 310);
DISPLAY INVISIBLE (-140 310);
FORCEPROP 1 LASTPIN (-150 300) BN 4
J 2
(-138 308);
DISPLAY 0.680851 (-138 308);
PAINT GREEN (-138 308);
FORCEPROP 2 LAST CDS_LIB standard
J 0
(-200 300);
DISPLAY INVISIBLE (-200 300);
FORCEPROP 1 LAST BODY_TYPE PLUMBING
J 2
(-200 350);
DISPLAY 0.872340 (-200 350);
PAINT GREEN (-200 350);
DISPLAY INVISIBLE (-200 350);
FORCEPROP 1 LAST HDL_TAP TRUE
J 2
(-525 175);
DISPLAY 0.872340 (-525 175);
DISPLAY INVISIBLE (-525 175);
FORCEPROP 1 LAST PATH I12
J 2
(-198 300);
DISPLAY 0.872340 (-198 300);
PAINT GREEN (-198 300);
DISPLAY INVISIBLE (-198 300);
FORCEADD TAP..1
(3225 1950);
FORCEPROP 3 LASTPIN (3175 1950) SIG_NAME M_G_CPU0_SB_DQS_DN<1>
J 0
(3185 1960);
DISPLAY 0.659574 (3185 1960);
PAINT MONO (3185 1960);
DISPLAY INVISIBLE (3185 1960);
FORCEPROP 1 LASTPIN (3175 1950) BN 1
J 0
(3163 1958);
DISPLAY 0.680851 (3163 1958);
PAINT GREEN (3163 1958);
FORCEPROP 2 LAST CDS_LIB standard
J 0
(3225 1950);
DISPLAY INVISIBLE (3225 1950);
FORCEPROP 1 LAST BODY_TYPE PLUMBING
J 0
(3225 2000);
DISPLAY 0.872340 (3225 2000);
PAINT GREEN (3225 2000);
DISPLAY INVISIBLE (3225 2000);
FORCEPROP 1 LAST HDL_TAP TRUE
J 0
(3550 1825);
DISPLAY 0.872340 (3550 1825);
DISPLAY INVISIBLE (3550 1825);
FORCEPROP 1 LAST PATH I120
J 0
(3223 1950);
DISPLAY 0.872340 (3223 1950);
PAINT GREEN (3223 1950);
DISPLAY INVISIBLE (3223 1950);
FORCEADD TAP..1
(3225 2000);
FORCEPROP 3 LASTPIN (3175 2000) SIG_NAME M_G_CPU0_SB_DQS_DN<2>
J 0
(3185 2010);
DISPLAY 0.659574 (3185 2010);
PAINT MONO (3185 2010);
DISPLAY INVISIBLE (3185 2010);
FORCEPROP 1 LASTPIN (3175 2000) BN 2
J 0
(3163 2008);
DISPLAY 0.680851 (3163 2008);
PAINT GREEN (3163 2008);
FORCEPROP 2 LAST CDS_LIB standard
J 0
(3225 2000);
DISPLAY INVISIBLE (3225 2000);
FORCEPROP 1 LAST BODY_TYPE PLUMBING
J 0
(3225 2050);
DISPLAY 0.872340 (3225 2050);
PAINT GREEN (3225 2050);
DISPLAY INVISIBLE (3225 2050);
FORCEPROP 1 LAST HDL_TAP TRUE
J 0
(3550 1875);
DISPLAY 0.872340 (3550 1875);
DISPLAY INVISIBLE (3550 1875);
FORCEPROP 1 LAST PATH I121
J 0
(3223 2000);
DISPLAY 0.872340 (3223 2000);
PAINT GREEN (3223 2000);
DISPLAY INVISIBLE (3223 2000);
FORCEADD TAP..1
(3225 2050);
FORCEPROP 3 LASTPIN (3175 2050) SIG_NAME M_G_CPU0_SB_DQS_DN<3>
J 0
(3185 2060);
DISPLAY 0.659574 (3185 2060);
PAINT MONO (3185 2060);
DISPLAY INVISIBLE (3185 2060);
FORCEPROP 1 LASTPIN (3175 2050) BN 3
J 0
(3163 2058);
DISPLAY 0.680851 (3163 2058);
PAINT GREEN (3163 2058);
FORCEPROP 2 LAST CDS_LIB standard
J 0
(3225 2050);
DISPLAY INVISIBLE (3225 2050);
FORCEPROP 1 LAST BODY_TYPE PLUMBING
J 0
(3225 2100);
DISPLAY 0.872340 (3225 2100);
PAINT GREEN (3225 2100);
DISPLAY INVISIBLE (3225 2100);
FORCEPROP 1 LAST HDL_TAP TRUE
J 0
(3550 1925);
DISPLAY 0.872340 (3550 1925);
DISPLAY INVISIBLE (3550 1925);
FORCEPROP 1 LAST PATH I122
J 0
(3223 2050);
DISPLAY 0.872340 (3223 2050);
PAINT GREEN (3223 2050);
DISPLAY INVISIBLE (3223 2050);
FORCEADD TAP..1
(3225 2100);
FORCEPROP 3 LASTPIN (3175 2100) SIG_NAME M_G_CPU0_SB_DQS_DN<4>
J 0
(3185 2110);
DISPLAY 0.659574 (3185 2110);
PAINT MONO (3185 2110);
DISPLAY INVISIBLE (3185 2110);
FORCEPROP 1 LASTPIN (3175 2100) BN 4
J 0
(3163 2108);
DISPLAY 0.680851 (3163 2108);
PAINT GREEN (3163 2108);
FORCEPROP 2 LAST CDS_LIB standard
J 0
(3225 2100);
DISPLAY INVISIBLE (3225 2100);
FORCEPROP 1 LAST BODY_TYPE PLUMBING
J 0
(3225 2150);
DISPLAY 0.872340 (3225 2150);
PAINT GREEN (3225 2150);
DISPLAY INVISIBLE (3225 2150);
FORCEPROP 1 LAST HDL_TAP TRUE
J 0
(3550 1975);
DISPLAY 0.872340 (3550 1975);
DISPLAY INVISIBLE (3550 1975);
FORCEPROP 1 LAST PATH I123
J 0
(3223 2100);
DISPLAY 0.872340 (3223 2100);
PAINT GREEN (3223 2100);
DISPLAY INVISIBLE (3223 2100);
FORCEADD TAP..1
(3225 2200);
FORCEPROP 3 LASTPIN (3175 2200) SIG_NAME M_G_CPU0_SB_DQS_DN<6>
J 0
(3185 2210);
DISPLAY 0.659574 (3185 2210);
PAINT MONO (3185 2210);
DISPLAY INVISIBLE (3185 2210);
FORCEPROP 1 LASTPIN (3175 2200) BN 6
J 0
(3163 2208);
DISPLAY 0.680851 (3163 2208);
PAINT GREEN (3163 2208);
FORCEPROP 2 LAST CDS_LIB standard
J 0
(3225 2200);
DISPLAY INVISIBLE (3225 2200);
FORCEPROP 1 LAST BODY_TYPE PLUMBING
J 0
(3225 2250);
DISPLAY 0.872340 (3225 2250);
PAINT GREEN (3225 2250);
DISPLAY INVISIBLE (3225 2250);
FORCEPROP 1 LAST HDL_TAP TRUE
J 0
(3550 2075);
DISPLAY 0.872340 (3550 2075);
DISPLAY INVISIBLE (3550 2075);
FORCEPROP 1 LAST PATH I124
J 0
(3223 2200);
DISPLAY 0.872340 (3223 2200);
PAINT GREEN (3223 2200);
DISPLAY INVISIBLE (3223 2200);
FORCEADD TAP..1
(3225 2150);
FORCEPROP 3 LASTPIN (3175 2150) SIG_NAME M_G_CPU0_SB_DQS_DN<5>
J 0
(3185 2160);
DISPLAY 0.659574 (3185 2160);
PAINT MONO (3185 2160);
DISPLAY INVISIBLE (3185 2160);
FORCEPROP 1 LASTPIN (3175 2150) BN 5
J 0
(3163 2158);
DISPLAY 0.680851 (3163 2158);
PAINT GREEN (3163 2158);
FORCEPROP 2 LAST CDS_LIB standard
J 0
(3225 2150);
DISPLAY INVISIBLE (3225 2150);
FORCEPROP 1 LAST BODY_TYPE PLUMBING
J 0
(3225 2200);
DISPLAY 0.872340 (3225 2200);
PAINT GREEN (3225 2200);
DISPLAY INVISIBLE (3225 2200);
FORCEPROP 1 LAST HDL_TAP TRUE
J 0
(3550 2025);
DISPLAY 0.872340 (3550 2025);
DISPLAY INVISIBLE (3550 2025);
FORCEPROP 1 LAST PATH I125
J 0
(3223 2150);
DISPLAY 0.872340 (3223 2150);
PAINT GREEN (3223 2150);
DISPLAY INVISIBLE (3223 2150);
FORCEADD TAP..1
(3225 2350);
FORCEPROP 3 LASTPIN (3175 2350) SIG_NAME M_G_CPU0_SB_DQS_DN<9>
J 0
(3185 2360);
DISPLAY 0.659574 (3185 2360);
PAINT MONO (3185 2360);
DISPLAY INVISIBLE (3185 2360);
FORCEPROP 1 LASTPIN (3175 2350) BN 9
J 0
(3163 2358);
DISPLAY 0.680851 (3163 2358);
PAINT GREEN (3163 2358);
FORCEPROP 2 LAST CDS_LIB standard
J 0
(3225 2350);
DISPLAY INVISIBLE (3225 2350);
FORCEPROP 1 LAST BODY_TYPE PLUMBING
J 0
(3225 2400);
DISPLAY 0.872340 (3225 2400);
PAINT GREEN (3225 2400);
DISPLAY INVISIBLE (3225 2400);
FORCEPROP 1 LAST HDL_TAP TRUE
J 0
(3550 2225);
DISPLAY 0.872340 (3550 2225);
DISPLAY INVISIBLE (3550 2225);
FORCEPROP 1 LAST PATH I126
J 0
(3223 2350);
DISPLAY 0.872340 (3223 2350);
PAINT GREEN (3223 2350);
DISPLAY INVISIBLE (3223 2350);
FORCEADD TAP..1
(3225 2300);
FORCEPROP 3 LASTPIN (3175 2300) SIG_NAME M_G_CPU0_SB_DQS_DN<8>
J 0
(3185 2310);
DISPLAY 0.659574 (3185 2310);
PAINT MONO (3185 2310);
DISPLAY INVISIBLE (3185 2310);
FORCEPROP 1 LASTPIN (3175 2300) BN 8
J 0
(3163 2308);
DISPLAY 0.680851 (3163 2308);
PAINT GREEN (3163 2308);
FORCEPROP 2 LAST CDS_LIB standard
J 0
(3225 2300);
DISPLAY INVISIBLE (3225 2300);
FORCEPROP 1 LAST BODY_TYPE PLUMBING
J 0
(3225 2350);
DISPLAY 0.872340 (3225 2350);
PAINT GREEN (3225 2350);
DISPLAY INVISIBLE (3225 2350);
FORCEPROP 1 LAST HDL_TAP TRUE
J 0
(3550 2175);
DISPLAY 0.872340 (3550 2175);
DISPLAY INVISIBLE (3550 2175);
FORCEPROP 1 LAST PATH I127
J 0
(3223 2300);
DISPLAY 0.872340 (3223 2300);
PAINT GREEN (3223 2300);
DISPLAY INVISIBLE (3223 2300);
FORCEADD TAP..1
(3225 2250);
FORCEPROP 3 LASTPIN (3175 2250) SIG_NAME M_G_CPU0_SB_DQS_DN<7>
J 0
(3185 2260);
DISPLAY 0.659574 (3185 2260);
PAINT MONO (3185 2260);
DISPLAY INVISIBLE (3185 2260);
FORCEPROP 1 LASTPIN (3175 2250) BN 7
J 0
(3163 2258);
DISPLAY 0.680851 (3163 2258);
PAINT GREEN (3163 2258);
FORCEPROP 2 LAST CDS_LIB standard
J 0
(3225 2250);
DISPLAY INVISIBLE (3225 2250);
FORCEPROP 1 LAST BODY_TYPE PLUMBING
J 0
(3225 2300);
DISPLAY 0.872340 (3225 2300);
PAINT GREEN (3225 2300);
DISPLAY INVISIBLE (3225 2300);
FORCEPROP 1 LAST HDL_TAP TRUE
J 0
(3550 2125);
DISPLAY 0.872340 (3550 2125);
DISPLAY INVISIBLE (3550 2125);
FORCEPROP 1 LAST PATH I128
J 0
(3223 2250);
DISPLAY 0.872340 (3223 2250);
PAINT GREEN (3223 2250);
DISPLAY INVISIBLE (3223 2250);
FORCEADD TAP..1
(3225 2450);
FORCEPROP 3 LASTPIN (3175 2450) SIG_NAME M_G_CPU0_SB_DQS_DP<0>
J 0
(3185 2460);
DISPLAY 0.659574 (3185 2460);
PAINT MONO (3185 2460);
DISPLAY INVISIBLE (3185 2460);
FORCEPROP 1 LASTPIN (3175 2450) BN 0
J 0
(3163 2458);
DISPLAY 0.680851 (3163 2458);
PAINT GREEN (3163 2458);
FORCEPROP 2 LAST CDS_LIB standard
J 0
(3225 2450);
DISPLAY INVISIBLE (3225 2450);
FORCEPROP 1 LAST BODY_TYPE PLUMBING
J 0
(3225 2500);
DISPLAY 0.872340 (3225 2500);
PAINT GREEN (3225 2500);
DISPLAY INVISIBLE (3225 2500);
FORCEPROP 1 LAST HDL_TAP TRUE
J 0
(3550 2325);
DISPLAY 0.872340 (3550 2325);
DISPLAY INVISIBLE (3550 2325);
FORCEPROP 1 LAST PATH I129
J 0
(3223 2450);
DISPLAY 0.872340 (3223 2450);
PAINT GREEN (3223 2450);
DISPLAY INVISIBLE (3223 2450);
FORCEADD TAP..1
R 2
(-200 250);
FORCEPROP 3 LASTPIN (-150 250) SIG_NAME M_G_CPU0_SB_CB<3>
J 0
(-140 260);
DISPLAY 0.659574 (-140 260);
PAINT MONO (-140 260);
DISPLAY INVISIBLE (-140 260);
FORCEPROP 1 LASTPIN (-150 250) BN 3
J 2
(-138 258);
DISPLAY 0.680851 (-138 258);
PAINT GREEN (-138 258);
FORCEPROP 2 LAST CDS_LIB standard
J 0
(-200 250);
DISPLAY INVISIBLE (-200 250);
FORCEPROP 1 LAST BODY_TYPE PLUMBING
J 2
(-200 300);
DISPLAY 0.872340 (-200 300);
PAINT GREEN (-200 300);
DISPLAY INVISIBLE (-200 300);
FORCEPROP 1 LAST HDL_TAP TRUE
J 2
(-525 125);
DISPLAY 0.872340 (-525 125);
DISPLAY INVISIBLE (-525 125);
FORCEPROP 1 LAST PATH I13
J 2
(-198 250);
DISPLAY 0.872340 (-198 250);
PAINT GREEN (-198 250);
DISPLAY INVISIBLE (-198 250);
FORCEADD TAP..1
(3225 2500);
FORCEPROP 3 LASTPIN (3175 2500) SIG_NAME M_G_CPU0_SB_DQS_DP<1>
J 0
(3185 2510);
DISPLAY 0.659574 (3185 2510);
PAINT MONO (3185 2510);
DISPLAY INVISIBLE (3185 2510);
FORCEPROP 1 LASTPIN (3175 2500) BN 1
J 0
(3163 2508);
DISPLAY 0.680851 (3163 2508);
PAINT GREEN (3163 2508);
FORCEPROP 2 LAST CDS_LIB standard
J 0
(3225 2500);
DISPLAY INVISIBLE (3225 2500);
FORCEPROP 1 LAST BODY_TYPE PLUMBING
J 0
(3225 2550);
DISPLAY 0.872340 (3225 2550);
PAINT GREEN (3225 2550);
DISPLAY INVISIBLE (3225 2550);
FORCEPROP 1 LAST HDL_TAP TRUE
J 0
(3550 2375);
DISPLAY 0.872340 (3550 2375);
DISPLAY INVISIBLE (3550 2375);
FORCEPROP 1 LAST PATH I130
J 0
(3223 2500);
DISPLAY 0.872340 (3223 2500);
PAINT GREEN (3223 2500);
DISPLAY INVISIBLE (3223 2500);
FORCEADD TAP..1
(3225 2550);
FORCEPROP 3 LASTPIN (3175 2550) SIG_NAME M_G_CPU0_SB_DQS_DP<2>
J 0
(3185 2560);
DISPLAY 0.659574 (3185 2560);
PAINT MONO (3185 2560);
DISPLAY INVISIBLE (3185 2560);
FORCEPROP 1 LASTPIN (3175 2550) BN 2
J 0
(3163 2558);
DISPLAY 0.680851 (3163 2558);
PAINT GREEN (3163 2558);
FORCEPROP 2 LAST CDS_LIB standard
J 0
(3225 2550);
DISPLAY INVISIBLE (3225 2550);
FORCEPROP 1 LAST BODY_TYPE PLUMBING
J 0
(3225 2600);
DISPLAY 0.872340 (3225 2600);
PAINT GREEN (3225 2600);
DISPLAY INVISIBLE (3225 2600);
FORCEPROP 1 LAST HDL_TAP TRUE
J 0
(3550 2425);
DISPLAY 0.872340 (3550 2425);
DISPLAY INVISIBLE (3550 2425);
FORCEPROP 1 LAST PATH I131
J 0
(3223 2550);
DISPLAY 0.872340 (3223 2550);
PAINT GREEN (3223 2550);
DISPLAY INVISIBLE (3223 2550);
FORCEADD TAP..1
(3225 2600);
FORCEPROP 3 LASTPIN (3175 2600) SIG_NAME M_G_CPU0_SB_DQS_DP<3>
J 0
(3185 2610);
DISPLAY 0.659574 (3185 2610);
PAINT MONO (3185 2610);
DISPLAY INVISIBLE (3185 2610);
FORCEPROP 1 LASTPIN (3175 2600) BN 3
J 0
(3163 2608);
DISPLAY 0.680851 (3163 2608);
PAINT GREEN (3163 2608);
FORCEPROP 2 LAST CDS_LIB standard
J 0
(3225 2600);
DISPLAY INVISIBLE (3225 2600);
FORCEPROP 1 LAST BODY_TYPE PLUMBING
J 0
(3225 2650);
DISPLAY 0.872340 (3225 2650);
PAINT GREEN (3225 2650);
DISPLAY INVISIBLE (3225 2650);
FORCEPROP 1 LAST HDL_TAP TRUE
J 0
(3550 2475);
DISPLAY 0.872340 (3550 2475);
DISPLAY INVISIBLE (3550 2475);
FORCEPROP 1 LAST PATH I132
J 0
(3223 2600);
DISPLAY 0.872340 (3223 2600);
PAINT GREEN (3223 2600);
DISPLAY INVISIBLE (3223 2600);
FORCEADD TAP..1
(3225 2750);
FORCEPROP 3 LASTPIN (3175 2750) SIG_NAME M_G_CPU0_SB_DQS_DP<6>
J 0
(3185 2760);
DISPLAY 0.659574 (3185 2760);
PAINT MONO (3185 2760);
DISPLAY INVISIBLE (3185 2760);
FORCEPROP 1 LASTPIN (3175 2750) BN 6
J 0
(3163 2758);
DISPLAY 0.680851 (3163 2758);
PAINT GREEN (3163 2758);
FORCEPROP 2 LAST CDS_LIB standard
J 0
(3225 2750);
DISPLAY INVISIBLE (3225 2750);
FORCEPROP 1 LAST BODY_TYPE PLUMBING
J 0
(3225 2800);
DISPLAY 0.872340 (3225 2800);
PAINT GREEN (3225 2800);
DISPLAY INVISIBLE (3225 2800);
FORCEPROP 1 LAST HDL_TAP TRUE
J 0
(3550 2625);
DISPLAY 0.872340 (3550 2625);
DISPLAY INVISIBLE (3550 2625);
FORCEPROP 1 LAST PATH I133
J 0
(3223 2750);
DISPLAY 0.872340 (3223 2750);
PAINT GREEN (3223 2750);
DISPLAY INVISIBLE (3223 2750);
FORCEADD TAP..1
(3225 2650);
FORCEPROP 3 LASTPIN (3175 2650) SIG_NAME M_G_CPU0_SB_DQS_DP<4>
J 0
(3185 2660);
DISPLAY 0.659574 (3185 2660);
PAINT MONO (3185 2660);
DISPLAY INVISIBLE (3185 2660);
FORCEPROP 1 LASTPIN (3175 2650) BN 4
J 0
(3163 2658);
DISPLAY 0.680851 (3163 2658);
PAINT GREEN (3163 2658);
FORCEPROP 2 LAST CDS_LIB standard
J 0
(3225 2650);
DISPLAY INVISIBLE (3225 2650);
FORCEPROP 1 LAST BODY_TYPE PLUMBING
J 0
(3225 2700);
DISPLAY 0.872340 (3225 2700);
PAINT GREEN (3225 2700);
DISPLAY INVISIBLE (3225 2700);
FORCEPROP 1 LAST HDL_TAP TRUE
J 0
(3550 2525);
DISPLAY 0.872340 (3550 2525);
DISPLAY INVISIBLE (3550 2525);
FORCEPROP 1 LAST PATH I134
J 0
(3223 2650);
DISPLAY 0.872340 (3223 2650);
PAINT GREEN (3223 2650);
DISPLAY INVISIBLE (3223 2650);
FORCEADD TAP..1
(3225 2700);
FORCEPROP 3 LASTPIN (3175 2700) SIG_NAME M_G_CPU0_SB_DQS_DP<5>
J 0
(3185 2710);
DISPLAY 0.659574 (3185 2710);
PAINT MONO (3185 2710);
DISPLAY INVISIBLE (3185 2710);
FORCEPROP 1 LASTPIN (3175 2700) BN 5
J 0
(3163 2708);
DISPLAY 0.680851 (3163 2708);
PAINT GREEN (3163 2708);
FORCEPROP 2 LAST CDS_LIB standard
J 0
(3225 2700);
DISPLAY INVISIBLE (3225 2700);
FORCEPROP 1 LAST BODY_TYPE PLUMBING
J 0
(3225 2750);
DISPLAY 0.872340 (3225 2750);
PAINT GREEN (3225 2750);
DISPLAY INVISIBLE (3225 2750);
FORCEPROP 1 LAST HDL_TAP TRUE
J 0
(3550 2575);
DISPLAY 0.872340 (3550 2575);
DISPLAY INVISIBLE (3550 2575);
FORCEPROP 1 LAST PATH I135
J 0
(3223 2700);
DISPLAY 0.872340 (3223 2700);
PAINT GREEN (3223 2700);
DISPLAY INVISIBLE (3223 2700);
FORCEADD TAP..1
(3225 2850);
FORCEPROP 3 LASTPIN (3175 2850) SIG_NAME M_G_CPU0_SB_DQS_DP<8>
J 0
(3185 2860);
DISPLAY 0.659574 (3185 2860);
PAINT MONO (3185 2860);
DISPLAY INVISIBLE (3185 2860);
FORCEPROP 1 LASTPIN (3175 2850) BN 8
J 0
(3163 2858);
DISPLAY 0.680851 (3163 2858);
PAINT GREEN (3163 2858);
FORCEPROP 2 LAST CDS_LIB standard
J 0
(3225 2850);
DISPLAY INVISIBLE (3225 2850);
FORCEPROP 1 LAST BODY_TYPE PLUMBING
J 0
(3225 2900);
DISPLAY 0.872340 (3225 2900);
PAINT GREEN (3225 2900);
DISPLAY INVISIBLE (3225 2900);
FORCEPROP 1 LAST HDL_TAP TRUE
J 0
(3550 2725);
DISPLAY 0.872340 (3550 2725);
DISPLAY INVISIBLE (3550 2725);
FORCEPROP 1 LAST PATH I136
J 0
(3223 2850);
DISPLAY 0.872340 (3223 2850);
PAINT GREEN (3223 2850);
DISPLAY INVISIBLE (3223 2850);
FORCEADD TAP..1
(3225 2900);
FORCEPROP 3 LASTPIN (3175 2900) SIG_NAME M_G_CPU0_SB_DQS_DP<9>
J 0
(3185 2910);
DISPLAY 0.659574 (3185 2910);
PAINT MONO (3185 2910);
DISPLAY INVISIBLE (3185 2910);
FORCEPROP 1 LASTPIN (3175 2900) BN 9
J 0
(3163 2908);
DISPLAY 0.680851 (3163 2908);
PAINT GREEN (3163 2908);
FORCEPROP 2 LAST CDS_LIB standard
J 0
(3225 2900);
DISPLAY INVISIBLE (3225 2900);
FORCEPROP 1 LAST BODY_TYPE PLUMBING
J 0
(3225 2950);
DISPLAY 0.872340 (3225 2950);
PAINT GREEN (3225 2950);
DISPLAY INVISIBLE (3225 2950);
FORCEPROP 1 LAST HDL_TAP TRUE
J 0
(3550 2775);
DISPLAY 0.872340 (3550 2775);
DISPLAY INVISIBLE (3550 2775);
FORCEPROP 1 LAST PATH I137
J 0
(3223 2900);
DISPLAY 0.872340 (3223 2900);
PAINT GREEN (3223 2900);
DISPLAY INVISIBLE (3223 2900);
FORCEADD TAP..1
(3225 2800);
FORCEPROP 3 LASTPIN (3175 2800) SIG_NAME M_G_CPU0_SB_DQS_DP<7>
J 0
(3185 2810);
DISPLAY 0.659574 (3185 2810);
PAINT MONO (3185 2810);
DISPLAY INVISIBLE (3185 2810);
FORCEPROP 1 LASTPIN (3175 2800) BN 7
J 0
(3163 2808);
DISPLAY 0.680851 (3163 2808);
PAINT GREEN (3163 2808);
FORCEPROP 2 LAST CDS_LIB standard
J 0
(3225 2800);
DISPLAY INVISIBLE (3225 2800);
FORCEPROP 1 LAST BODY_TYPE PLUMBING
J 0
(3225 2850);
DISPLAY 0.872340 (3225 2850);
PAINT GREEN (3225 2850);
DISPLAY INVISIBLE (3225 2850);
FORCEPROP 1 LAST HDL_TAP TRUE
J 0
(3550 2675);
DISPLAY 0.872340 (3550 2675);
DISPLAY INVISIBLE (3550 2675);
FORCEPROP 1 LAST PATH I138
J 0
(3223 2800);
DISPLAY 0.872340 (3223 2800);
PAINT GREEN (3223 2800);
DISPLAY INVISIBLE (3223 2800);
FORCEADD TAP..1
(3225 3100);
FORCEPROP 3 LASTPIN (3175 3100) SIG_NAME M_G_CPU0_SA_DQS_DN<1>
J 0
(3185 3110);
DISPLAY 0.659574 (3185 3110);
PAINT MONO (3185 3110);
DISPLAY INVISIBLE (3185 3110);
FORCEPROP 1 LASTPIN (3175 3100) BN 1
J 0
(3163 3108);
DISPLAY 0.680851 (3163 3108);
PAINT GREEN (3163 3108);
FORCEPROP 2 LAST CDS_LIB standard
J 0
(3225 3100);
DISPLAY INVISIBLE (3225 3100);
FORCEPROP 1 LAST BODY_TYPE PLUMBING
J 0
(3225 3150);
DISPLAY 0.872340 (3225 3150);
PAINT GREEN (3225 3150);
DISPLAY INVISIBLE (3225 3150);
FORCEPROP 1 LAST HDL_TAP TRUE
J 0
(3550 2975);
DISPLAY 0.872340 (3550 2975);
DISPLAY INVISIBLE (3550 2975);
FORCEPROP 1 LAST PATH I139
J 0
(3223 3100);
DISPLAY 0.872340 (3223 3100);
PAINT GREEN (3223 3100);
DISPLAY INVISIBLE (3223 3100);
FORCEADD TAP..1
R 2
(-200 400);
FORCEPROP 3 LASTPIN (-150 400) SIG_NAME M_G_CPU0_SB_CB<6>
J 0
(-140 410);
DISPLAY 0.659574 (-140 410);
PAINT MONO (-140 410);
DISPLAY INVISIBLE (-140 410);
FORCEPROP 1 LASTPIN (-150 400) BN 6
J 2
(-138 408);
DISPLAY 0.680851 (-138 408);
PAINT GREEN (-138 408);
FORCEPROP 2 LAST CDS_LIB standard
J 0
(-200 400);
DISPLAY INVISIBLE (-200 400);
FORCEPROP 1 LAST BODY_TYPE PLUMBING
J 2
(-200 450);
DISPLAY 0.872340 (-200 450);
PAINT GREEN (-200 450);
DISPLAY INVISIBLE (-200 450);
FORCEPROP 1 LAST HDL_TAP TRUE
J 2
(-525 275);
DISPLAY 0.872340 (-525 275);
DISPLAY INVISIBLE (-525 275);
FORCEPROP 1 LAST PATH I14
J 2
(-198 400);
DISPLAY 0.872340 (-198 400);
PAINT GREEN (-198 400);
DISPLAY INVISIBLE (-198 400);
FORCEADD TAP..1
(3225 3050);
FORCEPROP 3 LASTPIN (3175 3050) SIG_NAME M_G_CPU0_SA_DQS_DN<0>
J 0
(3185 3060);
DISPLAY 0.659574 (3185 3060);
PAINT MONO (3185 3060);
DISPLAY INVISIBLE (3185 3060);
FORCEPROP 1 LASTPIN (3175 3050) BN 0
J 0
(3163 3058);
DISPLAY 0.680851 (3163 3058);
PAINT GREEN (3163 3058);
FORCEPROP 2 LAST CDS_LIB standard
J 0
(3225 3050);
DISPLAY INVISIBLE (3225 3050);
FORCEPROP 1 LAST BODY_TYPE PLUMBING
J 0
(3225 3100);
DISPLAY 0.872340 (3225 3100);
PAINT GREEN (3225 3100);
DISPLAY INVISIBLE (3225 3100);
FORCEPROP 1 LAST HDL_TAP TRUE
J 0
(3550 2925);
DISPLAY 0.872340 (3550 2925);
DISPLAY INVISIBLE (3550 2925);
FORCEPROP 1 LAST PATH I140
J 0
(3223 3050);
DISPLAY 0.872340 (3223 3050);
PAINT GREEN (3223 3050);
DISPLAY INVISIBLE (3223 3050);
FORCEADD TAP..1
(3225 3250);
FORCEPROP 3 LASTPIN (3175 3250) SIG_NAME M_G_CPU0_SA_DQS_DN<4>
J 0
(3185 3260);
DISPLAY 0.659574 (3185 3260);
PAINT MONO (3185 3260);
DISPLAY INVISIBLE (3185 3260);
FORCEPROP 1 LASTPIN (3175 3250) BN 4
J 0
(3163 3258);
DISPLAY 0.680851 (3163 3258);
PAINT GREEN (3163 3258);
FORCEPROP 2 LAST CDS_LIB standard
J 0
(3225 3250);
DISPLAY INVISIBLE (3225 3250);
FORCEPROP 1 LAST BODY_TYPE PLUMBING
J 0
(3225 3300);
DISPLAY 0.872340 (3225 3300);
PAINT GREEN (3225 3300);
DISPLAY INVISIBLE (3225 3300);
FORCEPROP 1 LAST HDL_TAP TRUE
J 0
(3550 3125);
DISPLAY 0.872340 (3550 3125);
DISPLAY INVISIBLE (3550 3125);
FORCEPROP 1 LAST PATH I141
J 0
(3223 3250);
DISPLAY 0.872340 (3223 3250);
PAINT GREEN (3223 3250);
DISPLAY INVISIBLE (3223 3250);
FORCEADD TAP..1
(3225 3150);
FORCEPROP 3 LASTPIN (3175 3150) SIG_NAME M_G_CPU0_SA_DQS_DN<2>
J 0
(3185 3160);
DISPLAY 0.659574 (3185 3160);
PAINT MONO (3185 3160);
DISPLAY INVISIBLE (3185 3160);
FORCEPROP 1 LASTPIN (3175 3150) BN 2
J 0
(3163 3158);
DISPLAY 0.680851 (3163 3158);
PAINT GREEN (3163 3158);
FORCEPROP 2 LAST CDS_LIB standard
J 0
(3225 3150);
DISPLAY INVISIBLE (3225 3150);
FORCEPROP 1 LAST BODY_TYPE PLUMBING
J 0
(3225 3200);
DISPLAY 0.872340 (3225 3200);
PAINT GREEN (3225 3200);
DISPLAY INVISIBLE (3225 3200);
FORCEPROP 1 LAST HDL_TAP TRUE
J 0
(3550 3025);
DISPLAY 0.872340 (3550 3025);
DISPLAY INVISIBLE (3550 3025);
FORCEPROP 1 LAST PATH I142
J 0
(3223 3150);
DISPLAY 0.872340 (3223 3150);
PAINT GREEN (3223 3150);
DISPLAY INVISIBLE (3223 3150);
FORCEADD TAP..1
(3225 3200);
FORCEPROP 3 LASTPIN (3175 3200) SIG_NAME M_G_CPU0_SA_DQS_DN<3>
J 0
(3185 3210);
DISPLAY 0.659574 (3185 3210);
PAINT MONO (3185 3210);
DISPLAY INVISIBLE (3185 3210);
FORCEPROP 1 LASTPIN (3175 3200) BN 3
J 0
(3163 3208);
DISPLAY 0.680851 (3163 3208);
PAINT GREEN (3163 3208);
FORCEPROP 2 LAST CDS_LIB standard
J 0
(3225 3200);
DISPLAY INVISIBLE (3225 3200);
FORCEPROP 1 LAST BODY_TYPE PLUMBING
J 0
(3225 3250);
DISPLAY 0.872340 (3225 3250);
PAINT GREEN (3225 3250);
DISPLAY INVISIBLE (3225 3250);
FORCEPROP 1 LAST HDL_TAP TRUE
J 0
(3550 3075);
DISPLAY 0.872340 (3550 3075);
DISPLAY INVISIBLE (3550 3075);
FORCEPROP 1 LAST PATH I143
J 0
(3223 3200);
DISPLAY 0.872340 (3223 3200);
PAINT GREEN (3223 3200);
DISPLAY INVISIBLE (3223 3200);
FORCEADD TAP..1
(3225 3300);
FORCEPROP 3 LASTPIN (3175 3300) SIG_NAME M_G_CPU0_SA_DQS_DN<5>
J 0
(3185 3310);
DISPLAY 0.659574 (3185 3310);
PAINT MONO (3185 3310);
DISPLAY INVISIBLE (3185 3310);
FORCEPROP 1 LASTPIN (3175 3300) BN 5
J 0
(3163 3308);
DISPLAY 0.680851 (3163 3308);
PAINT GREEN (3163 3308);
FORCEPROP 2 LAST CDS_LIB standard
J 0
(3225 3300);
DISPLAY INVISIBLE (3225 3300);
FORCEPROP 1 LAST BODY_TYPE PLUMBING
J 0
(3225 3350);
DISPLAY 0.872340 (3225 3350);
PAINT GREEN (3225 3350);
DISPLAY INVISIBLE (3225 3350);
FORCEPROP 1 LAST HDL_TAP TRUE
J 0
(3550 3175);
DISPLAY 0.872340 (3550 3175);
DISPLAY INVISIBLE (3550 3175);
FORCEPROP 1 LAST PATH I144
J 0
(3223 3300);
DISPLAY 0.872340 (3223 3300);
PAINT GREEN (3223 3300);
DISPLAY INVISIBLE (3223 3300);
FORCEADD TAP..1
(3225 3350);
FORCEPROP 3 LASTPIN (3175 3350) SIG_NAME M_G_CPU0_SA_DQS_DN<6>
J 0
(3185 3360);
DISPLAY 0.659574 (3185 3360);
PAINT MONO (3185 3360);
DISPLAY INVISIBLE (3185 3360);
FORCEPROP 1 LASTPIN (3175 3350) BN 6
J 0
(3163 3358);
DISPLAY 0.680851 (3163 3358);
PAINT GREEN (3163 3358);
FORCEPROP 2 LAST CDS_LIB standard
J 0
(3225 3350);
DISPLAY INVISIBLE (3225 3350);
FORCEPROP 1 LAST BODY_TYPE PLUMBING
J 0
(3225 3400);
DISPLAY 0.872340 (3225 3400);
PAINT GREEN (3225 3400);
DISPLAY INVISIBLE (3225 3400);
FORCEPROP 1 LAST HDL_TAP TRUE
J 0
(3550 3225);
DISPLAY 0.872340 (3550 3225);
DISPLAY INVISIBLE (3550 3225);
FORCEPROP 1 LAST PATH I145
J 0
(3223 3350);
DISPLAY 0.872340 (3223 3350);
PAINT GREEN (3223 3350);
DISPLAY INVISIBLE (3223 3350);
FORCEADD TAP..1
(3225 3400);
FORCEPROP 3 LASTPIN (3175 3400) SIG_NAME M_G_CPU0_SA_DQS_DN<7>
J 0
(3185 3410);
DISPLAY 0.659574 (3185 3410);
PAINT MONO (3185 3410);
DISPLAY INVISIBLE (3185 3410);
FORCEPROP 1 LASTPIN (3175 3400) BN 7
J 0
(3163 3408);
DISPLAY 0.680851 (3163 3408);
PAINT GREEN (3163 3408);
FORCEPROP 2 LAST CDS_LIB standard
J 0
(3225 3400);
DISPLAY INVISIBLE (3225 3400);
FORCEPROP 1 LAST BODY_TYPE PLUMBING
J 0
(3225 3450);
DISPLAY 0.872340 (3225 3450);
PAINT GREEN (3225 3450);
DISPLAY INVISIBLE (3225 3450);
FORCEPROP 1 LAST HDL_TAP TRUE
J 0
(3550 3275);
DISPLAY 0.872340 (3550 3275);
DISPLAY INVISIBLE (3550 3275);
FORCEPROP 1 LAST PATH I146
J 0
(3223 3400);
DISPLAY 0.872340 (3223 3400);
PAINT GREEN (3223 3400);
DISPLAY INVISIBLE (3223 3400);
FORCEADD TAP..1
(3225 3500);
FORCEPROP 3 LASTPIN (3175 3500) SIG_NAME M_G_CPU0_SA_DQS_DN<9>
J 0
(3185 3510);
DISPLAY 0.659574 (3185 3510);
PAINT MONO (3185 3510);
DISPLAY INVISIBLE (3185 3510);
FORCEPROP 1 LASTPIN (3175 3500) BN 9
J 0
(3163 3508);
DISPLAY 0.680851 (3163 3508);
PAINT GREEN (3163 3508);
FORCEPROP 2 LAST CDS_LIB standard
J 0
(3225 3500);
DISPLAY INVISIBLE (3225 3500);
FORCEPROP 1 LAST BODY_TYPE PLUMBING
J 0
(3225 3550);
DISPLAY 0.872340 (3225 3550);
PAINT GREEN (3225 3550);
DISPLAY INVISIBLE (3225 3550);
FORCEPROP 1 LAST HDL_TAP TRUE
J 0
(3550 3375);
DISPLAY 0.872340 (3550 3375);
DISPLAY INVISIBLE (3550 3375);
FORCEPROP 1 LAST PATH I147
J 0
(3223 3500);
DISPLAY 0.872340 (3223 3500);
PAINT GREEN (3223 3500);
DISPLAY INVISIBLE (3223 3500);
FORCEADD TAP..1
(3225 3450);
FORCEPROP 3 LASTPIN (3175 3450) SIG_NAME M_G_CPU0_SA_DQS_DN<8>
J 0
(3185 3460);
DISPLAY 0.659574 (3185 3460);
PAINT MONO (3185 3460);
DISPLAY INVISIBLE (3185 3460);
FORCEPROP 1 LASTPIN (3175 3450) BN 8
J 0
(3163 3458);
DISPLAY 0.680851 (3163 3458);
PAINT GREEN (3163 3458);
FORCEPROP 2 LAST CDS_LIB standard
J 0
(3225 3450);
DISPLAY INVISIBLE (3225 3450);
FORCEPROP 1 LAST BODY_TYPE PLUMBING
J 0
(3225 3500);
DISPLAY 0.872340 (3225 3500);
PAINT GREEN (3225 3500);
DISPLAY INVISIBLE (3225 3500);
FORCEPROP 1 LAST HDL_TAP TRUE
J 0
(3550 3325);
DISPLAY 0.872340 (3550 3325);
DISPLAY INVISIBLE (3550 3325);
FORCEPROP 1 LAST PATH I148
J 0
(3223 3450);
DISPLAY 0.872340 (3223 3450);
PAINT GREEN (3223 3450);
DISPLAY INVISIBLE (3223 3450);
FORCEADD TAP..1
(3225 3600);
FORCEPROP 3 LASTPIN (3175 3600) SIG_NAME M_G_CPU0_SA_DQS_DP<0>
J 0
(3185 3610);
DISPLAY 0.659574 (3185 3610);
PAINT MONO (3185 3610);
DISPLAY INVISIBLE (3185 3610);
FORCEPROP 1 LASTPIN (3175 3600) BN 0
J 0
(3163 3608);
DISPLAY 0.680851 (3163 3608);
PAINT GREEN (3163 3608);
FORCEPROP 2 LAST CDS_LIB standard
J 0
(3225 3600);
DISPLAY INVISIBLE (3225 3600);
FORCEPROP 1 LAST BODY_TYPE PLUMBING
J 0
(3225 3650);
DISPLAY 0.872340 (3225 3650);
PAINT GREEN (3225 3650);
DISPLAY INVISIBLE (3225 3650);
FORCEPROP 1 LAST HDL_TAP TRUE
J 0
(3550 3475);
DISPLAY 0.872340 (3550 3475);
DISPLAY INVISIBLE (3550 3475);
FORCEPROP 1 LAST PATH I149
J 0
(3223 3600);
DISPLAY 0.872340 (3223 3600);
PAINT GREEN (3223 3600);
DISPLAY INVISIBLE (3223 3600);
FORCEADD TAP..1
R 2
(-200 350);
FORCEPROP 3 LASTPIN (-150 350) SIG_NAME M_G_CPU0_SB_CB<5>
J 0
(-140 360);
DISPLAY 0.659574 (-140 360);
PAINT MONO (-140 360);
DISPLAY INVISIBLE (-140 360);
FORCEPROP 1 LASTPIN (-150 350) BN 5
J 2
(-138 358);
DISPLAY 0.680851 (-138 358);
PAINT GREEN (-138 358);
FORCEPROP 2 LAST CDS_LIB standard
J 0
(-200 350);
DISPLAY INVISIBLE (-200 350);
FORCEPROP 1 LAST BODY_TYPE PLUMBING
J 2
(-200 400);
DISPLAY 0.872340 (-200 400);
PAINT GREEN (-200 400);
DISPLAY INVISIBLE (-200 400);
FORCEPROP 1 LAST HDL_TAP TRUE
J 2
(-525 225);
DISPLAY 0.872340 (-525 225);
DISPLAY INVISIBLE (-525 225);
FORCEPROP 1 LAST PATH I15
J 2
(-198 350);
DISPLAY 0.872340 (-198 350);
PAINT GREEN (-198 350);
DISPLAY INVISIBLE (-198 350);
FORCEADD TAP..1
(3225 3650);
FORCEPROP 3 LASTPIN (3175 3650) SIG_NAME M_G_CPU0_SA_DQS_DP<1>
J 0
(3185 3660);
DISPLAY 0.659574 (3185 3660);
PAINT MONO (3185 3660);
DISPLAY INVISIBLE (3185 3660);
FORCEPROP 1 LASTPIN (3175 3650) BN 1
J 0
(3163 3658);
DISPLAY 0.680851 (3163 3658);
PAINT GREEN (3163 3658);
FORCEPROP 2 LAST CDS_LIB standard
J 0
(3225 3650);
DISPLAY INVISIBLE (3225 3650);
FORCEPROP 1 LAST BODY_TYPE PLUMBING
J 0
(3225 3700);
DISPLAY 0.872340 (3225 3700);
PAINT GREEN (3225 3700);
DISPLAY INVISIBLE (3225 3700);
FORCEPROP 1 LAST HDL_TAP TRUE
J 0
(3550 3525);
DISPLAY 0.872340 (3550 3525);
DISPLAY INVISIBLE (3550 3525);
FORCEPROP 1 LAST PATH I150
J 0
(3223 3650);
DISPLAY 0.872340 (3223 3650);
PAINT GREEN (3223 3650);
DISPLAY INVISIBLE (3223 3650);
FORCEADD TAP..1
(3225 3750);
FORCEPROP 3 LASTPIN (3175 3750) SIG_NAME M_G_CPU0_SA_DQS_DP<3>
J 0
(3185 3760);
DISPLAY 0.659574 (3185 3760);
PAINT MONO (3185 3760);
DISPLAY INVISIBLE (3185 3760);
FORCEPROP 1 LASTPIN (3175 3750) BN 3
J 0
(3163 3758);
DISPLAY 0.680851 (3163 3758);
PAINT GREEN (3163 3758);
FORCEPROP 2 LAST CDS_LIB standard
J 0
(3225 3750);
DISPLAY INVISIBLE (3225 3750);
FORCEPROP 1 LAST BODY_TYPE PLUMBING
J 0
(3225 3800);
DISPLAY 0.872340 (3225 3800);
PAINT GREEN (3225 3800);
DISPLAY INVISIBLE (3225 3800);
FORCEPROP 1 LAST HDL_TAP TRUE
J 0
(3550 3625);
DISPLAY 0.872340 (3550 3625);
DISPLAY INVISIBLE (3550 3625);
FORCEPROP 1 LAST PATH I151
J 0
(3223 3750);
DISPLAY 0.872340 (3223 3750);
PAINT GREEN (3223 3750);
DISPLAY INVISIBLE (3223 3750);
FORCEADD TAP..1
(3225 3700);
FORCEPROP 3 LASTPIN (3175 3700) SIG_NAME M_G_CPU0_SA_DQS_DP<2>
J 0
(3185 3710);
DISPLAY 0.659574 (3185 3710);
PAINT MONO (3185 3710);
DISPLAY INVISIBLE (3185 3710);
FORCEPROP 1 LASTPIN (3175 3700) BN 2
J 0
(3163 3708);
DISPLAY 0.680851 (3163 3708);
PAINT GREEN (3163 3708);
FORCEPROP 2 LAST CDS_LIB standard
J 0
(3225 3700);
DISPLAY INVISIBLE (3225 3700);
FORCEPROP 1 LAST BODY_TYPE PLUMBING
J 0
(3225 3750);
DISPLAY 0.872340 (3225 3750);
PAINT GREEN (3225 3750);
DISPLAY INVISIBLE (3225 3750);
FORCEPROP 1 LAST HDL_TAP TRUE
J 0
(3550 3575);
DISPLAY 0.872340 (3550 3575);
DISPLAY INVISIBLE (3550 3575);
FORCEPROP 1 LAST PATH I152
J 0
(3223 3700);
DISPLAY 0.872340 (3223 3700);
PAINT GREEN (3223 3700);
DISPLAY INVISIBLE (3223 3700);
FORCEADD TAP..1
(3225 3800);
FORCEPROP 3 LASTPIN (3175 3800) SIG_NAME M_G_CPU0_SA_DQS_DP<4>
J 0
(3185 3810);
DISPLAY 0.659574 (3185 3810);
PAINT MONO (3185 3810);
DISPLAY INVISIBLE (3185 3810);
FORCEPROP 1 LASTPIN (3175 3800) BN 4
J 0
(3163 3808);
DISPLAY 0.680851 (3163 3808);
PAINT GREEN (3163 3808);
FORCEPROP 2 LAST CDS_LIB standard
J 0
(3225 3800);
DISPLAY INVISIBLE (3225 3800);
FORCEPROP 1 LAST BODY_TYPE PLUMBING
J 0
(3225 3850);
DISPLAY 0.872340 (3225 3850);
PAINT GREEN (3225 3850);
DISPLAY INVISIBLE (3225 3850);
FORCEPROP 1 LAST HDL_TAP TRUE
J 0
(3550 3675);
DISPLAY 0.872340 (3550 3675);
DISPLAY INVISIBLE (3550 3675);
FORCEPROP 1 LAST PATH I153
J 0
(3223 3800);
DISPLAY 0.872340 (3223 3800);
PAINT GREEN (3223 3800);
DISPLAY INVISIBLE (3223 3800);
FORCEADD TAP..1
(3225 3850);
FORCEPROP 3 LASTPIN (3175 3850) SIG_NAME M_G_CPU0_SA_DQS_DP<5>
J 0
(3185 3860);
DISPLAY 0.659574 (3185 3860);
PAINT MONO (3185 3860);
DISPLAY INVISIBLE (3185 3860);
FORCEPROP 1 LASTPIN (3175 3850) BN 5
J 0
(3163 3858);
DISPLAY 0.680851 (3163 3858);
PAINT GREEN (3163 3858);
FORCEPROP 2 LAST CDS_LIB standard
J 0
(3225 3850);
DISPLAY INVISIBLE (3225 3850);
FORCEPROP 1 LAST BODY_TYPE PLUMBING
J 0
(3225 3900);
DISPLAY 0.872340 (3225 3900);
PAINT GREEN (3225 3900);
DISPLAY INVISIBLE (3225 3900);
FORCEPROP 1 LAST HDL_TAP TRUE
J 0
(3550 3725);
DISPLAY 0.872340 (3550 3725);
DISPLAY INVISIBLE (3550 3725);
FORCEPROP 1 LAST PATH I154
J 0
(3223 3850);
DISPLAY 0.872340 (3223 3850);
PAINT GREEN (3223 3850);
DISPLAY INVISIBLE (3223 3850);
FORCEADD TAP..1
(3225 3900);
FORCEPROP 3 LASTPIN (3175 3900) SIG_NAME M_G_CPU0_SA_DQS_DP<6>
J 0
(3185 3910);
DISPLAY 0.659574 (3185 3910);
PAINT MONO (3185 3910);
DISPLAY INVISIBLE (3185 3910);
FORCEPROP 1 LASTPIN (3175 3900) BN 6
J 0
(3163 3908);
DISPLAY 0.680851 (3163 3908);
PAINT GREEN (3163 3908);
FORCEPROP 2 LAST CDS_LIB standard
J 0
(3225 3900);
DISPLAY INVISIBLE (3225 3900);
FORCEPROP 1 LAST BODY_TYPE PLUMBING
J 0
(3225 3950);
DISPLAY 0.872340 (3225 3950);
PAINT GREEN (3225 3950);
DISPLAY INVISIBLE (3225 3950);
FORCEPROP 1 LAST HDL_TAP TRUE
J 0
(3550 3775);
DISPLAY 0.872340 (3550 3775);
DISPLAY INVISIBLE (3550 3775);
FORCEPROP 1 LAST PATH I155
J 0
(3223 3900);
DISPLAY 0.872340 (3223 3900);
PAINT GREEN (3223 3900);
DISPLAY INVISIBLE (3223 3900);
FORCEADD TAP..1
(3225 4000);
FORCEPROP 3 LASTPIN (3175 4000) SIG_NAME M_G_CPU0_SA_DQS_DP<8>
J 0
(3185 4010);
DISPLAY 0.659574 (3185 4010);
PAINT MONO (3185 4010);
DISPLAY INVISIBLE (3185 4010);
FORCEPROP 1 LASTPIN (3175 4000) BN 8
J 0
(3163 4008);
DISPLAY 0.680851 (3163 4008);
PAINT GREEN (3163 4008);
FORCEPROP 2 LAST CDS_LIB standard
J 0
(3225 4000);
DISPLAY INVISIBLE (3225 4000);
FORCEPROP 1 LAST BODY_TYPE PLUMBING
J 0
(3225 4050);
DISPLAY 0.872340 (3225 4050);
PAINT GREEN (3225 4050);
DISPLAY INVISIBLE (3225 4050);
FORCEPROP 1 LAST HDL_TAP TRUE
J 0
(3550 3875);
DISPLAY 0.872340 (3550 3875);
DISPLAY INVISIBLE (3550 3875);
FORCEPROP 1 LAST PATH I156
J 0
(3223 4000);
DISPLAY 0.872340 (3223 4000);
PAINT GREEN (3223 4000);
DISPLAY INVISIBLE (3223 4000);
FORCEADD TAP..1
(3225 3950);
FORCEPROP 3 LASTPIN (3175 3950) SIG_NAME M_G_CPU0_SA_DQS_DP<7>
J 0
(3185 3960);
DISPLAY 0.659574 (3185 3960);
PAINT MONO (3185 3960);
DISPLAY INVISIBLE (3185 3960);
FORCEPROP 1 LASTPIN (3175 3950) BN 7
J 0
(3163 3958);
DISPLAY 0.680851 (3163 3958);
PAINT GREEN (3163 3958);
FORCEPROP 2 LAST CDS_LIB standard
J 0
(3225 3950);
DISPLAY INVISIBLE (3225 3950);
FORCEPROP 1 LAST BODY_TYPE PLUMBING
J 0
(3225 4000);
DISPLAY 0.872340 (3225 4000);
PAINT GREEN (3225 4000);
DISPLAY INVISIBLE (3225 4000);
FORCEPROP 1 LAST HDL_TAP TRUE
J 0
(3550 3825);
DISPLAY 0.872340 (3550 3825);
DISPLAY INVISIBLE (3550 3825);
FORCEPROP 1 LAST PATH I157
J 0
(3223 3950);
DISPLAY 0.872340 (3223 3950);
PAINT GREEN (3223 3950);
DISPLAY INVISIBLE (3223 3950);
FORCEADD TAP..1
(3225 4050);
FORCEPROP 3 LASTPIN (3175 4050) SIG_NAME M_G_CPU0_SA_DQS_DP<9>
J 0
(3185 4060);
DISPLAY 0.659574 (3185 4060);
PAINT MONO (3185 4060);
DISPLAY INVISIBLE (3185 4060);
FORCEPROP 1 LASTPIN (3175 4050) BN 9
J 0
(3163 4058);
DISPLAY 0.680851 (3163 4058);
PAINT GREEN (3163 4058);
FORCEPROP 2 LAST CDS_LIB standard
J 0
(3225 4050);
DISPLAY INVISIBLE (3225 4050);
FORCEPROP 1 LAST BODY_TYPE PLUMBING
J 0
(3225 4100);
DISPLAY 0.872340 (3225 4100);
PAINT GREEN (3225 4100);
DISPLAY INVISIBLE (3225 4100);
FORCEPROP 1 LAST HDL_TAP TRUE
J 0
(3550 3925);
DISPLAY 0.872340 (3550 3925);
DISPLAY INVISIBLE (3550 3925);
FORCEPROP 1 LAST PATH I158
J 0
(3223 4050);
DISPLAY 0.872340 (3223 4050);
PAINT GREEN (3223 4050);
DISPLAY INVISIBLE (3223 4050);
FORCEADD OFFPAGE..2
(4325 475);
FORCEPROP 2 LAST $XR1 95 
J 0
(4604 475);
DISPLAY 0.638298 (4604 475);
PAINT MONO (4604 475);
FORCEPROP 2 LAST $XR0 94 
J 0
(4514 475);
DISPLAY 0.638298 (4514 475);
PAINT MONO (4514 475);
FORCEPROP 2 LAST CDS_LIB standard
J 0
(4325 475);
PAINT MONO (4325 475);
DISPLAY INVISIBLE (4325 475);
FORCEPROP 1 LAST OFFPAGE TRUE
J 0
(4650 350);
DISPLAY 1.170213 (4650 350);
PAINT GREEN (4650 350);
DISPLAY INVISIBLE (4650 350);
FORCEPROP 1 LAST COMMENT_BODY TRUE
J 0
(4280 380);
DISPLAY 1.170213 (4280 380);
PAINT GREEN (4280 380);
DISPLAY INVISIBLE (4280 380);
FORCEPROP 2 LAST PATH I159
J 0
(4500 550);
DISPLAY 1.021277 (4500 550);
DISPLAY INVISIBLE (4500 550);
FORCEADD TAP..1
R 2
(-200 500);
FORCEPROP 3 LASTPIN (-150 500) SIG_NAME M_G_CPU0_SB_DQ<0>
J 0
(-140 510);
DISPLAY 0.659574 (-140 510);
PAINT MONO (-140 510);
DISPLAY INVISIBLE (-140 510);
FORCEPROP 1 LASTPIN (-150 500) BN 0
J 2
(-138 508);
DISPLAY 0.680851 (-138 508);
PAINT GREEN (-138 508);
FORCEPROP 2 LAST CDS_LIB standard
J 0
(-200 500);
DISPLAY INVISIBLE (-200 500);
FORCEPROP 1 LAST BODY_TYPE PLUMBING
J 2
(-200 550);
DISPLAY 0.872340 (-200 550);
PAINT GREEN (-200 550);
DISPLAY INVISIBLE (-200 550);
FORCEPROP 1 LAST HDL_TAP TRUE
J 2
(-525 375);
DISPLAY 0.872340 (-525 375);
DISPLAY INVISIBLE (-525 375);
FORCEPROP 1 LAST PATH I16
J 2
(-198 500);
DISPLAY 0.872340 (-198 500);
PAINT GREEN (-198 500);
DISPLAY INVISIBLE (-198 500);
FORCEADD OFFPAGE..2
(4325 775);
FORCEPROP 2 LAST $XR1 95 
J 0
(4604 775);
DISPLAY 0.638298 (4604 775);
PAINT MONO (4604 775);
FORCEPROP 2 LAST $XR0 94 
J 0
(4514 775);
DISPLAY 0.638298 (4514 775);
PAINT MONO (4514 775);
FORCEPROP 2 LAST CDS_LIB standard
J 0
(4325 775);
PAINT MONO (4325 775);
DISPLAY INVISIBLE (4325 775);
FORCEPROP 1 LAST OFFPAGE TRUE
J 0
(4650 650);
DISPLAY 1.170213 (4650 650);
PAINT GREEN (4650 650);
DISPLAY INVISIBLE (4650 650);
FORCEPROP 1 LAST COMMENT_BODY TRUE
J 0
(4280 680);
DISPLAY 1.170213 (4280 680);
PAINT GREEN (4280 680);
DISPLAY INVISIBLE (4280 680);
FORCEPROP 2 LAST PATH I160
J 0
(4500 850);
DISPLAY 1.021277 (4500 850);
DISPLAY INVISIBLE (4500 850);
FORCEADD OFFPAGE..2
(4325 900);
FORCEPROP 2 LAST $XR1 95 
J 0
(4604 900);
DISPLAY 0.638298 (4604 900);
PAINT MONO (4604 900);
FORCEPROP 2 LAST $XR0 94 
J 0
(4514 900);
DISPLAY 0.638298 (4514 900);
PAINT MONO (4514 900);
FORCEPROP 2 LAST CDS_LIB standard
J 0
(4325 900);
PAINT MONO (4325 900);
DISPLAY INVISIBLE (4325 900);
FORCEPROP 1 LAST OFFPAGE TRUE
J 0
(4650 775);
DISPLAY 1.170213 (4650 775);
PAINT GREEN (4650 775);
DISPLAY INVISIBLE (4650 775);
FORCEPROP 1 LAST COMMENT_BODY TRUE
J 0
(4280 805);
DISPLAY 1.170213 (4280 805);
PAINT GREEN (4280 805);
DISPLAY INVISIBLE (4280 805);
FORCEPROP 2 LAST PATH I161
J 0
(4500 975);
DISPLAY 1.021277 (4500 975);
DISPLAY INVISIBLE (4500 975);
FORCEADD OFFPAGE..3
(4325 1275);
FORCEPROP 2 LAST $XR1 95 
J 0
(4629 1275);
DISPLAY 0.638298 (4629 1275);
PAINT MONO (4629 1275);
FORCEPROP 2 LAST $XR0 94 
J 0
(4539 1275);
DISPLAY 0.638298 (4539 1275);
PAINT MONO (4539 1275);
FORCEPROP 2 LAST CDS_LIB standard
J 2
(4325 1275);
DISPLAY INVISIBLE (4325 1275);
FORCEPROP 1 LAST OFFPAGE TRUE
J 0
(4650 1150);
DISPLAY 0.872340 (4650 1150);
DISPLAY INVISIBLE (4650 1150);
FORCEPROP 1 LAST COMMENT_BODY TRUE
J 0
(4275 1175);
DISPLAY 0.872340 (4275 1175);
PAINT GREEN (4275 1175);
DISPLAY INVISIBLE (4275 1175);
FORCEPROP 2 LAST PATH I162
J 0
(4525 1350);
DISPLAY 1.021277 (4525 1350);
DISPLAY INVISIBLE (4525 1350);
FORCEADD OFFPAGE..2
(4325 1400);
FORCEPROP 2 LAST $XR1 95 
J 0
(4604 1400);
DISPLAY 0.638298 (4604 1400);
PAINT MONO (4604 1400);
FORCEPROP 2 LAST $XR0 94 
J 0
(4514 1400);
DISPLAY 0.638298 (4514 1400);
PAINT MONO (4514 1400);
FORCEPROP 2 LAST CDS_LIB standard
J 0
(4325 1400);
PAINT MONO (4325 1400);
DISPLAY INVISIBLE (4325 1400);
FORCEPROP 1 LAST OFFPAGE TRUE
J 0
(4650 1275);
DISPLAY 1.170213 (4650 1275);
PAINT GREEN (4650 1275);
DISPLAY INVISIBLE (4650 1275);
FORCEPROP 1 LAST COMMENT_BODY TRUE
J 0
(4280 1305);
DISPLAY 1.170213 (4280 1305);
PAINT GREEN (4280 1305);
DISPLAY INVISIBLE (4280 1305);
FORCEPROP 2 LAST PATH I163
J 0
(4500 1475);
DISPLAY 1.021277 (4500 1475);
DISPLAY INVISIBLE (4500 1475);
FORCEADD OFFPAGE..3
(4325 1775);
FORCEPROP 2 LAST $XR1 95 
J 0
(4629 1775);
DISPLAY 0.638298 (4629 1775);
PAINT MONO (4629 1775);
FORCEPROP 2 LAST $XR0 94 
J 0
(4539 1775);
DISPLAY 0.638298 (4539 1775);
PAINT MONO (4539 1775);
FORCEPROP 2 LAST CDS_LIB standard
J 2
(4325 1775);
DISPLAY INVISIBLE (4325 1775);
FORCEPROP 1 LAST OFFPAGE TRUE
J 0
(4650 1650);
DISPLAY 0.872340 (4650 1650);
DISPLAY INVISIBLE (4650 1650);
FORCEPROP 1 LAST COMMENT_BODY TRUE
J 0
(4275 1675);
DISPLAY 0.872340 (4275 1675);
PAINT GREEN (4275 1675);
DISPLAY INVISIBLE (4275 1675);
FORCEPROP 2 LAST PATH I164
J 0
(4525 1850);
DISPLAY 1.021277 (4525 1850);
DISPLAY INVISIBLE (4525 1850);
FORCEADD OFFPAGE..3
(4325 2375);
FORCEPROP 2 LAST $XR1 95 
J 0
(4629 2375);
DISPLAY 0.638298 (4629 2375);
PAINT MONO (4629 2375);
FORCEPROP 2 LAST $XR0 94 
J 0
(4539 2375);
DISPLAY 0.638298 (4539 2375);
PAINT MONO (4539 2375);
FORCEPROP 2 LAST CDS_LIB standard
J 2
(4325 2375);
DISPLAY INVISIBLE (4325 2375);
FORCEPROP 1 LAST OFFPAGE TRUE
J 0
(4650 2250);
DISPLAY 0.872340 (4650 2250);
DISPLAY INVISIBLE (4650 2250);
FORCEPROP 1 LAST COMMENT_BODY TRUE
J 0
(4275 2275);
DISPLAY 0.872340 (4275 2275);
PAINT GREEN (4275 2275);
DISPLAY INVISIBLE (4275 2275);
FORCEPROP 2 LAST PATH I165
J 0
(4525 2450);
DISPLAY 1.021277 (4525 2450);
DISPLAY INVISIBLE (4525 2450);
FORCEADD OFFPAGE..3
(4325 2925);
FORCEPROP 2 LAST $XR1 95 
J 0
(4629 2925);
DISPLAY 0.638298 (4629 2925);
PAINT MONO (4629 2925);
FORCEPROP 2 LAST $XR0 94 
J 0
(4539 2925);
DISPLAY 0.638298 (4539 2925);
PAINT MONO (4539 2925);
FORCEPROP 2 LAST CDS_LIB standard
J 2
(4325 2925);
DISPLAY INVISIBLE (4325 2925);
FORCEPROP 1 LAST OFFPAGE TRUE
J 0
(4650 2800);
DISPLAY 0.872340 (4650 2800);
DISPLAY INVISIBLE (4650 2800);
FORCEPROP 1 LAST COMMENT_BODY TRUE
J 0
(4275 2825);
DISPLAY 0.872340 (4275 2825);
PAINT GREEN (4275 2825);
DISPLAY INVISIBLE (4275 2825);
FORCEPROP 2 LAST PATH I166
J 0
(4525 3000);
DISPLAY 1.021277 (4525 3000);
DISPLAY INVISIBLE (4525 3000);
FORCEADD OFFPAGE..3
(4325 3525);
FORCEPROP 2 LAST $XR1 95 
J 0
(4629 3525);
DISPLAY 0.638298 (4629 3525);
PAINT MONO (4629 3525);
FORCEPROP 2 LAST $XR0 94 
J 0
(4539 3525);
DISPLAY 0.638298 (4539 3525);
PAINT MONO (4539 3525);
FORCEPROP 2 LAST CDS_LIB standard
J 2
(4325 3525);
DISPLAY INVISIBLE (4325 3525);
FORCEPROP 1 LAST OFFPAGE TRUE
J 0
(4650 3400);
DISPLAY 0.872340 (4650 3400);
DISPLAY INVISIBLE (4650 3400);
FORCEPROP 1 LAST COMMENT_BODY TRUE
J 0
(4275 3425);
DISPLAY 0.872340 (4275 3425);
PAINT GREEN (4275 3425);
DISPLAY INVISIBLE (4275 3425);
FORCEPROP 2 LAST PATH I167
J 0
(4525 3600);
DISPLAY 1.021277 (4525 3600);
DISPLAY INVISIBLE (4525 3600);
FORCEADD OFFPAGE..3
(4325 4075);
FORCEPROP 2 LAST $XR1 95 
J 0
(4629 4075);
DISPLAY 0.638298 (4629 4075);
PAINT MONO (4629 4075);
FORCEPROP 2 LAST $XR0 94 
J 0
(4539 4075);
DISPLAY 0.638298 (4539 4075);
PAINT MONO (4539 4075);
FORCEPROP 2 LAST CDS_LIB standard
J 2
(4325 4075);
DISPLAY INVISIBLE (4325 4075);
FORCEPROP 1 LAST OFFPAGE TRUE
J 0
(4650 3950);
DISPLAY 0.872340 (4650 3950);
DISPLAY INVISIBLE (4650 3950);
FORCEPROP 1 LAST COMMENT_BODY TRUE
J 0
(4275 3975);
DISPLAY 0.872340 (4275 3975);
PAINT GREEN (4275 3975);
DISPLAY INVISIBLE (4275 3975);
FORCEPROP 2 LAST PATH I168
J 0
(4525 4150);
DISPLAY 1.021277 (4525 4150);
DISPLAY INVISIBLE (4525 4150);
FORCEADD SOCKET4677_AZIF0045P001C01CS..14
(1525 1950);
FORCEPROP 1 LAST PART_NUMBER DGA^7000023
J 0
(425 4300);
DISPLAY 0.723404 (425 4300);
PAINT GREEN (425 4300);
DISPLAY INVISIBLE (425 4300);
FORCEPROP 2 LAST PART_TYPE SMLF
J 0
(425 4475);
DISPLAY 1.021277 (425 4475);
FORCEPROP 1 LAST MATERIAL IO
J 0
(425 4225);
DISPLAY 0.723404 (425 4225);
PAINT GREEN (425 4225);
FORCEPROP 2 LAST VALUE SOCKET4677_AZIF0045-P001C01CS
J 0
(425 4425);
DISPLAY 1.021277 (425 4425);
FORCEPROP 1 LAST $LOCATION U2
J 0
(425 4375);
DISPLAY 0.723404 (425 4375);
PAINT GREEN (425 4375);
FORCEPROP 0 LASTPIN (2750 100) $PN EA48
J 0
(2760 110);
DISPLAY 0.680851 (2760 110);
PAINT MONO (2760 110);
FORCEPROP 0 LASTPIN (2750 150) $PN DY47
J 0
(2760 160);
DISPLAY 0.680851 (2760 160);
PAINT MONO (2760 160);
FORCEPROP 0 LASTPIN (2750 -150) $PN CW50
J 0
(2760 -140);
DISPLAY 0.680851 (2760 -140);
PAINT MONO (2760 -140);
FORCEPROP 0 LASTPIN (2750 -50) $PN DU48
J 0
(2760 -40);
DISPLAY 0.680851 (2760 -40);
PAINT MONO (2760 -40);
FORCEPROP 0 LASTPIN (2750 0) $PN DV47
J 0
(2760 10);
DISPLAY 0.680851 (2760 10);
PAINT MONO (2760 10);
FORCEPROP 0 LASTPIN (300 -150) $PN DR45
J 2
(290 -140);
DISPLAY 0.680851 (290 -140);
PAINT MONO (290 -140);
FORCEPROP 0 LASTPIN (300 -100) $PN DL45
J 2
(290 -90);
DISPLAY 0.680851 (290 -90);
PAINT MONO (290 -90);
FORCEPROP 0 LASTPIN (300 -50) $PN DN45
J 2
(290 -40);
DISPLAY 0.680851 (290 -40);
PAINT MONO (290 -40);
FORCEPROP 0 LASTPIN (300 0) $PN DJ45
J 2
(290 10);
DISPLAY 0.680851 (290 10);
PAINT MONO (290 10);
FORCEPROP 0 LASTPIN (2750 1450) $PN DJ52
J 0
(2760 1460);
DISPLAY 0.680851 (2760 1460);
PAINT MONO (2760 1460);
FORCEPROP 0 LASTPIN (2750 1500) $PN DR52
J 0
(2760 1510);
DISPLAY 0.680851 (2760 1510);
PAINT MONO (2760 1510);
FORCEPROP 0 LASTPIN (2750 1550) $PN DK51
J 0
(2760 1560);
DISPLAY 0.680851 (2760 1560);
PAINT MONO (2760 1560);
FORCEPROP 0 LASTPIN (2750 1600) $PN DP51
J 0
(2760 1610);
DISPLAY 0.680851 (2760 1610);
PAINT MONO (2760 1610);
FORCEPROP 0 LASTPIN (2750 1650) $PN DL50
J 0
(2760 1660);
DISPLAY 0.680851 (2760 1660);
PAINT MONO (2760 1660);
FORCEPROP 0 LASTPIN (2750 1700) $PN DN50
J 0
(2760 1710);
DISPLAY 0.680851 (2760 1710);
PAINT MONO (2760 1710);
FORCEPROP 0 LASTPIN (2750 1750) $PN DK44
J 0
(2760 1760);
DISPLAY 0.680851 (2760 1760);
PAINT MONO (2760 1760);
FORCEPROP 0 LASTPIN (300 2500) $PN DV75
J 2
(290 2510);
DISPLAY 0.680851 (290 2510);
PAINT MONO (290 2510);
FORCEPROP 0 LASTPIN (300 2550) $PN DU74
J 2
(290 2560);
DISPLAY 0.680851 (290 2560);
PAINT MONO (290 2560);
FORCEPROP 0 LASTPIN (300 2600) $PN DY75
J 2
(290 2610);
DISPLAY 0.680851 (290 2610);
PAINT MONO (290 2610);
FORCEPROP 0 LASTPIN (300 2650) $PN EA74
J 2
(290 2660);
DISPLAY 0.680851 (290 2660);
PAINT MONO (290 2660);
FORCEPROP 0 LASTPIN (300 2700) $PN DU72
J 2
(290 2710);
DISPLAY 0.680851 (290 2710);
PAINT MONO (290 2710);
FORCEPROP 0 LASTPIN (300 2750) $PN DV71
J 2
(290 2760);
DISPLAY 0.680851 (290 2760);
PAINT MONO (290 2760);
FORCEPROP 0 LASTPIN (300 2800) $PN EA72
J 2
(290 2810);
DISPLAY 0.680851 (290 2810);
PAINT MONO (290 2810);
FORCEPROP 0 LASTPIN (300 2850) $PN DY71
J 2
(290 2860);
DISPLAY 0.680851 (290 2860);
PAINT MONO (290 2860);
FORCEPROP 0 LASTPIN (300 2900) $PN DL72
J 2
(290 2910);
DISPLAY 0.680851 (290 2910);
PAINT MONO (290 2910);
FORCEPROP 0 LASTPIN (300 2950) $PN DK71
J 2
(290 2960);
DISPLAY 0.680851 (290 2960);
PAINT MONO (290 2960);
FORCEPROP 0 LASTPIN (300 3000) $PN DN72
J 2
(290 3010);
DISPLAY 0.680851 (290 3010);
PAINT MONO (290 3010);
FORCEPROP 0 LASTPIN (300 3050) $PN DP71
J 2
(290 3060);
DISPLAY 0.680851 (290 3060);
PAINT MONO (290 3060);
FORCEPROP 0 LASTPIN (300 3100) $PN DK69
J 2
(290 3110);
DISPLAY 0.680851 (290 3110);
PAINT MONO (290 3110);
FORCEPROP 0 LASTPIN (300 3150) $PN DL68
J 2
(290 3160);
DISPLAY 0.680851 (290 3160);
PAINT MONO (290 3160);
FORCEPROP 0 LASTPIN (300 3200) $PN DP69
J 2
(290 3210);
DISPLAY 0.680851 (290 3210);
PAINT MONO (290 3210);
FORCEPROP 0 LASTPIN (300 3250) $PN DN68
J 2
(290 3260);
DISPLAY 0.680851 (290 3260);
PAINT MONO (290 3260);
FORCEPROP 0 LASTPIN (300 3300) $PN DV63
J 2
(290 3310);
DISPLAY 0.680851 (290 3310);
PAINT MONO (290 3310);
FORCEPROP 0 LASTPIN (300 3350) $PN DU62
J 2
(290 3360);
DISPLAY 0.680851 (290 3360);
PAINT MONO (290 3360);
FORCEPROP 0 LASTPIN (300 3400) $PN DY63
J 2
(290 3410);
DISPLAY 0.680851 (290 3410);
PAINT MONO (290 3410);
FORCEPROP 0 LASTPIN (300 3450) $PN EA62
J 2
(290 3460);
DISPLAY 0.680851 (290 3460);
PAINT MONO (290 3460);
FORCEPROP 0 LASTPIN (300 3500) $PN DU60
J 2
(290 3510);
DISPLAY 0.680851 (290 3510);
PAINT MONO (290 3510);
FORCEPROP 0 LASTPIN (300 3550) $PN DV59
J 2
(290 3560);
DISPLAY 0.680851 (290 3560);
PAINT MONO (290 3560);
FORCEPROP 0 LASTPIN (300 3600) $PN EA60
J 2
(290 3610);
DISPLAY 0.680851 (290 3610);
PAINT MONO (290 3610);
FORCEPROP 0 LASTPIN (300 3650) $PN DY59
J 2
(290 3660);
DISPLAY 0.680851 (290 3660);
PAINT MONO (290 3660);
FORCEPROP 0 LASTPIN (300 3700) $PN DL66
J 2
(290 3710);
DISPLAY 0.680851 (290 3710);
PAINT MONO (290 3710);
FORCEPROP 0 LASTPIN (300 3750) $PN DK65
J 2
(290 3760);
DISPLAY 0.680851 (290 3760);
PAINT MONO (290 3760);
FORCEPROP 0 LASTPIN (300 3800) $PN DN66
J 2
(290 3810);
DISPLAY 0.680851 (290 3810);
PAINT MONO (290 3810);
FORCEPROP 0 LASTPIN (300 3850) $PN DP65
J 2
(290 3860);
DISPLAY 0.680851 (290 3860);
PAINT MONO (290 3860);
FORCEPROP 0 LASTPIN (300 3900) $PN DK63
J 2
(290 3910);
DISPLAY 0.680851 (290 3910);
PAINT MONO (290 3910);
FORCEPROP 0 LASTPIN (300 3950) $PN DL62
J 2
(290 3960);
DISPLAY 0.680851 (290 3960);
PAINT MONO (290 3960);
FORCEPROP 0 LASTPIN (300 4000) $PN DP63
J 2
(290 4010);
DISPLAY 0.680851 (290 4010);
PAINT MONO (290 4010);
FORCEPROP 0 LASTPIN (300 4050) $PN DN62
J 2
(290 4060);
DISPLAY 0.680851 (290 4060);
PAINT MONO (290 4060);
FORCEPROP 0 LASTPIN (2750 3050) $PN DV73
J 0
(2760 3060);
DISPLAY 0.680851 (2760 3060);
PAINT MONO (2760 3060);
FORCEPROP 0 LASTPIN (2750 3100) $PN DJ70
J 0
(2760 3110);
DISPLAY 0.680851 (2760 3110);
PAINT MONO (2760 3110);
FORCEPROP 0 LASTPIN (2750 3150) $PN DT61
J 0
(2760 3160);
DISPLAY 0.680851 (2760 3160);
PAINT MONO (2760 3160);
FORCEPROP 0 LASTPIN (2750 3200) $PN DL64
J 0
(2760 3210);
DISPLAY 0.680851 (2760 3210);
PAINT MONO (2760 3210);
FORCEPROP 0 LASTPIN (2750 3250) $PN DL58
J 0
(2760 3260);
DISPLAY 0.680851 (2760 3260);
PAINT MONO (2760 3260);
FORCEPROP 0 LASTPIN (2750 3300) $PN EB73
J 0
(2760 3310);
DISPLAY 0.680851 (2760 3310);
PAINT MONO (2760 3310);
FORCEPROP 0 LASTPIN (2750 3350) $PN DR70
J 0
(2760 3360);
DISPLAY 0.680851 (2760 3360);
PAINT MONO (2760 3360);
FORCEPROP 0 LASTPIN (2750 3400) $PN EB61
J 0
(2760 3410);
DISPLAY 0.680851 (2760 3410);
PAINT MONO (2760 3410);
FORCEPROP 0 LASTPIN (2750 3450) $PN DR64
J 0
(2760 3460);
DISPLAY 0.680851 (2760 3460);
PAINT MONO (2760 3460);
FORCEPROP 0 LASTPIN (2750 3500) $PN DR58
J 0
(2760 3510);
DISPLAY 0.680851 (2760 3510);
PAINT MONO (2760 3510);
FORCEPROP 0 LASTPIN (2750 3600) $PN DT73
J 0
(2760 3610);
DISPLAY 0.680851 (2760 3610);
PAINT MONO (2760 3610);
FORCEPROP 0 LASTPIN (2750 3650) $PN DL70
J 0
(2760 3660);
DISPLAY 0.680851 (2760 3660);
PAINT MONO (2760 3660);
FORCEPROP 0 LASTPIN (2750 3700) $PN DV61
J 0
(2760 3710);
DISPLAY 0.680851 (2760 3710);
PAINT MONO (2760 3710);
FORCEPROP 0 LASTPIN (2750 3750) $PN DJ64
J 0
(2760 3760);
DISPLAY 0.680851 (2760 3760);
PAINT MONO (2760 3760);
FORCEPROP 0 LASTPIN (2750 3800) $PN DJ58
J 0
(2760 3810);
DISPLAY 0.680851 (2760 3810);
PAINT MONO (2760 3810);
FORCEPROP 0 LASTPIN (2750 3850) $PN DY73
J 0
(2760 3860);
DISPLAY 0.680851 (2760 3860);
PAINT MONO (2760 3860);
FORCEPROP 0 LASTPIN (2750 3900) $PN DN70
J 0
(2760 3910);
DISPLAY 0.680851 (2760 3910);
PAINT MONO (2760 3910);
FORCEPROP 0 LASTPIN (2750 3950) $PN DY61
J 0
(2760 3960);
DISPLAY 0.680851 (2760 3960);
PAINT MONO (2760 3960);
FORCEPROP 0 LASTPIN (2750 4000) $PN DN64
J 0
(2760 4010);
DISPLAY 0.680851 (2760 4010);
PAINT MONO (2760 4010);
FORCEPROP 0 LASTPIN (2750 4050) $PN DN58
J 0
(2760 4060);
DISPLAY 0.680851 (2760 4060);
PAINT MONO (2760 4060);
FORCEPROP 0 LASTPIN (300 2100) $PN DL60
J 2
(290 2110);
DISPLAY 0.680851 (290 2110);
PAINT MONO (290 2110);
FORCEPROP 0 LASTPIN (300 2150) $PN DK59
J 2
(290 2160);
DISPLAY 0.680851 (290 2160);
PAINT MONO (290 2160);
FORCEPROP 0 LASTPIN (300 2200) $PN DN60
J 2
(290 2210);
DISPLAY 0.680851 (290 2210);
PAINT MONO (290 2210);
FORCEPROP 0 LASTPIN (300 2250) $PN DP59
J 2
(290 2260);
DISPLAY 0.680851 (290 2260);
PAINT MONO (290 2260);
FORCEPROP 0 LASTPIN (300 2300) $PN DK57
J 2
(290 2310);
DISPLAY 0.680851 (290 2310);
PAINT MONO (290 2310);
FORCEPROP 0 LASTPIN (300 2350) $PN DL56
J 2
(290 2360);
DISPLAY 0.680851 (290 2360);
PAINT MONO (290 2360);
FORCEPROP 0 LASTPIN (300 2400) $PN DP57
J 2
(290 2410);
DISPLAY 0.680851 (290 2410);
PAINT MONO (290 2410);
FORCEPROP 0 LASTPIN (300 2450) $PN DN56
J 2
(290 2460);
DISPLAY 0.680851 (290 2460);
PAINT MONO (290 2460);
FORCEPROP 0 LASTPIN (2750 1400) $PN DL43
J 0
(2760 1410);
DISPLAY 0.680851 (2760 1410);
PAINT MONO (2760 1410);
FORCEPROP 0 LASTPIN (2750 950) $PN DN43
J 0
(2760 960);
DISPLAY 0.680851 (2760 960);
PAINT MONO (2760 960);
FORCEPROP 0 LASTPIN (2750 1000) $PN DP44
J 0
(2760 1010);
DISPLAY 0.680851 (2760 1010);
PAINT MONO (2760 1010);
FORCEPROP 0 LASTPIN (2750 1050) $PN DV44
J 0
(2760 1060);
DISPLAY 0.680851 (2760 1060);
PAINT MONO (2760 1060);
FORCEPROP 0 LASTPIN (2750 1100) $PN DY44
J 0
(2760 1110);
DISPLAY 0.680851 (2760 1110);
PAINT MONO (2760 1110);
FORCEPROP 0 LASTPIN (2750 1150) $PN DU43
J 0
(2760 1160);
DISPLAY 0.680851 (2760 1160);
PAINT MONO (2760 1160);
FORCEPROP 0 LASTPIN (2750 1200) $PN EA43
J 0
(2760 1210);
DISPLAY 0.680851 (2760 1210);
PAINT MONO (2760 1210);
FORCEPROP 0 LASTPIN (2750 1250) $PN DT42
J 0
(2760 1260);
DISPLAY 0.680851 (2760 1260);
PAINT MONO (2760 1260);
FORCEPROP 0 LASTPIN (300 500) $PN DL35
J 2
(290 510);
DISPLAY 0.680851 (290 510);
PAINT MONO (290 510);
FORCEPROP 0 LASTPIN (300 550) $PN DK34
J 2
(290 560);
DISPLAY 0.680851 (290 560);
PAINT MONO (290 560);
FORCEPROP 0 LASTPIN (300 600) $PN DN35
J 2
(290 610);
DISPLAY 0.680851 (290 610);
PAINT MONO (290 610);
FORCEPROP 0 LASTPIN (300 650) $PN DP34
J 2
(290 660);
DISPLAY 0.680851 (290 660);
PAINT MONO (290 660);
FORCEPROP 0 LASTPIN (300 700) $PN DK32
J 2
(290 710);
DISPLAY 0.680851 (290 710);
PAINT MONO (290 710);
FORCEPROP 0 LASTPIN (300 750) $PN DL31
J 2
(290 760);
DISPLAY 0.680851 (290 760);
PAINT MONO (290 760);
FORCEPROP 0 LASTPIN (300 800) $PN DP32
J 2
(290 810);
DISPLAY 0.680851 (290 810);
PAINT MONO (290 810);
FORCEPROP 0 LASTPIN (300 850) $PN DN31
J 2
(290 860);
DISPLAY 0.680851 (290 860);
PAINT MONO (290 860);
FORCEPROP 0 LASTPIN (300 900) $PN DN29
J 2
(290 910);
DISPLAY 0.680851 (290 910);
PAINT MONO (290 910);
FORCEPROP 0 LASTPIN (300 950) $PN DK28
J 2
(290 960);
DISPLAY 0.680851 (290 960);
PAINT MONO (290 960);
FORCEPROP 0 LASTPIN (300 1000) $PN DL29
J 2
(290 1010);
DISPLAY 0.680851 (290 1010);
PAINT MONO (290 1010);
FORCEPROP 0 LASTPIN (300 1050) $PN DP28
J 2
(290 1060);
DISPLAY 0.680851 (290 1060);
PAINT MONO (290 1060);
FORCEPROP 0 LASTPIN (300 1100) $PN DK26
J 2
(290 1110);
DISPLAY 0.680851 (290 1110);
PAINT MONO (290 1110);
FORCEPROP 0 LASTPIN (300 1150) $PN DL25
J 2
(290 1160);
DISPLAY 0.680851 (290 1160);
PAINT MONO (290 1160);
FORCEPROP 0 LASTPIN (300 1200) $PN DP26
J 2
(290 1210);
DISPLAY 0.680851 (290 1210);
PAINT MONO (290 1210);
FORCEPROP 0 LASTPIN (300 1250) $PN DN25
J 2
(290 1260);
DISPLAY 0.680851 (290 1260);
PAINT MONO (290 1260);
FORCEPROP 0 LASTPIN (300 1300) $PN DV26
J 2
(290 1310);
DISPLAY 0.680851 (290 1310);
PAINT MONO (290 1310);
FORCEPROP 0 LASTPIN (300 1350) $PN DU25
J 2
(290 1360);
DISPLAY 0.680851 (290 1360);
PAINT MONO (290 1360);
FORCEPROP 0 LASTPIN (300 1400) $PN DY26
J 2
(290 1410);
DISPLAY 0.680851 (290 1410);
PAINT MONO (290 1410);
FORCEPROP 0 LASTPIN (300 1450) $PN EA25
J 2
(290 1460);
DISPLAY 0.680851 (290 1460);
PAINT MONO (290 1460);
FORCEPROP 0 LASTPIN (300 1500) $PN DU23
J 2
(290 1510);
DISPLAY 0.680851 (290 1510);
PAINT MONO (290 1510);
FORCEPROP 0 LASTPIN (300 1550) $PN DV22
J 2
(290 1560);
DISPLAY 0.680851 (290 1560);
PAINT MONO (290 1560);
FORCEPROP 0 LASTPIN (300 1600) $PN EA23
J 2
(290 1610);
DISPLAY 0.680851 (290 1610);
PAINT MONO (290 1610);
FORCEPROP 0 LASTPIN (300 1650) $PN DY22
J 2
(290 1660);
DISPLAY 0.680851 (290 1660);
PAINT MONO (290 1660);
FORCEPROP 0 LASTPIN (300 1700) $PN EK8
J 2
(290 1710);
DISPLAY 0.680851 (290 1710);
PAINT MONO (290 1710);
FORCEPROP 0 LASTPIN (300 1750) $PN EH8
J 2
(290 1760);
DISPLAY 0.680851 (290 1760);
PAINT MONO (290 1760);
FORCEPROP 0 LASTPIN (300 1800) $PN EP8
J 2
(290 1810);
DISPLAY 0.680851 (290 1810);
PAINT MONO (290 1810);
FORCEPROP 0 LASTPIN (300 1850) $PN ET8
J 2
(290 1860);
DISPLAY 0.680851 (290 1860);
PAINT MONO (290 1860);
FORCEPROP 0 LASTPIN (300 1900) $PN EK6
J 2
(290 1910);
DISPLAY 0.680851 (290 1910);
PAINT MONO (290 1910);
FORCEPROP 0 LASTPIN (300 1950) $PN EJ5
J 2
(290 1960);
DISPLAY 0.680851 (290 1960);
PAINT MONO (290 1960);
FORCEPROP 0 LASTPIN (300 2000) $PN EP4
J 2
(290 2010);
DISPLAY 0.680851 (290 2010);
PAINT MONO (290 2010);
FORCEPROP 0 LASTPIN (300 2050) $PN EM4
J 2
(290 2060);
DISPLAY 0.680851 (290 2060);
PAINT MONO (290 2060);
FORCEPROP 0 LASTPIN (2750 1900) $PN DJ33
J 0
(2760 1910);
DISPLAY 0.680851 (2760 1910);
PAINT MONO (2760 1910);
FORCEPROP 0 LASTPIN (2750 1950) $PN DJ27
J 0
(2760 1960);
DISPLAY 0.680851 (2760 1960);
PAINT MONO (2760 1960);
FORCEPROP 0 LASTPIN (2750 2000) $PN DV24
J 0
(2760 2010);
DISPLAY 0.680851 (2760 2010);
PAINT MONO (2760 2010);
FORCEPROP 0 LASTPIN (2750 2050) $PN EP6
J 0
(2760 2060);
DISPLAY 0.680851 (2760 2060);
PAINT MONO (2760 2060);
FORCEPROP 0 LASTPIN (2750 2100) $PN EB36
J 0
(2760 2110);
DISPLAY 0.680851 (2760 2110);
PAINT MONO (2760 2110);
FORCEPROP 0 LASTPIN (2750 2150) $PN DR33
J 0
(2760 2160);
DISPLAY 0.680851 (2760 2160);
PAINT MONO (2760 2160);
FORCEPROP 0 LASTPIN (2750 2200) $PN DN27
J 0
(2760 2210);
DISPLAY 0.680851 (2760 2210);
PAINT MONO (2760 2210);
FORCEPROP 0 LASTPIN (2750 2250) $PN EB24
J 0
(2760 2260);
DISPLAY 0.680851 (2760 2260);
PAINT MONO (2760 2260);
FORCEPROP 0 LASTPIN (2750 2300) $PN EM6
J 0
(2760 2310);
DISPLAY 0.680851 (2760 2310);
PAINT MONO (2760 2310);
FORCEPROP 0 LASTPIN (2750 2350) $PN DV36
J 0
(2760 2360);
DISPLAY 0.680851 (2760 2360);
PAINT MONO (2760 2360);
FORCEPROP 0 LASTPIN (2750 2450) $PN DL33
J 0
(2760 2460);
DISPLAY 0.680851 (2760 2460);
PAINT MONO (2760 2460);
FORCEPROP 0 LASTPIN (2750 2500) $PN DL27
J 0
(2760 2510);
DISPLAY 0.680851 (2760 2510);
PAINT MONO (2760 2510);
FORCEPROP 0 LASTPIN (2750 2550) $PN DT24
J 0
(2760 2560);
DISPLAY 0.680851 (2760 2560);
PAINT MONO (2760 2560);
FORCEPROP 0 LASTPIN (2750 2600) $PN EN7
J 0
(2760 2610);
DISPLAY 0.680851 (2760 2610);
PAINT MONO (2760 2610);
FORCEPROP 0 LASTPIN (2750 2650) $PN DY36
J 0
(2760 2660);
DISPLAY 0.680851 (2760 2660);
PAINT MONO (2760 2660);
FORCEPROP 0 LASTPIN (2750 2700) $PN DN33
J 0
(2760 2710);
DISPLAY 0.680851 (2760 2710);
PAINT MONO (2760 2710);
FORCEPROP 0 LASTPIN (2750 2750) $PN DR27
J 0
(2760 2760);
DISPLAY 0.680851 (2760 2760);
PAINT MONO (2760 2760);
FORCEPROP 0 LASTPIN (2750 2800) $PN DY24
J 0
(2760 2810);
DISPLAY 0.680851 (2760 2810);
PAINT MONO (2760 2810);
FORCEPROP 0 LASTPIN (2750 2850) $PN EN5
J 0
(2760 2860);
DISPLAY 0.680851 (2760 2860);
PAINT MONO (2760 2860);
FORCEPROP 0 LASTPIN (2750 2900) $PN DT36
J 0
(2760 2910);
DISPLAY 0.680851 (2760 2910);
PAINT MONO (2760 2910);
FORCEPROP 0 LASTPIN (300 100) $PN DU35
J 2
(290 110);
DISPLAY 0.680851 (290 110);
PAINT MONO (290 110);
FORCEPROP 0 LASTPIN (300 150) $PN DV34
J 2
(290 160);
DISPLAY 0.680851 (290 160);
PAINT MONO (290 160);
FORCEPROP 0 LASTPIN (300 200) $PN EA35
J 2
(290 210);
DISPLAY 0.680851 (290 210);
PAINT MONO (290 210);
FORCEPROP 0 LASTPIN (300 250) $PN DY34
J 2
(290 260);
DISPLAY 0.680851 (290 260);
PAINT MONO (290 260);
FORCEPROP 0 LASTPIN (300 300) $PN DV38
J 2
(290 310);
DISPLAY 0.680851 (290 310);
PAINT MONO (290 310);
FORCEPROP 0 LASTPIN (300 350) $PN DU37
J 2
(290 360);
DISPLAY 0.680851 (290 360);
PAINT MONO (290 360);
FORCEPROP 0 LASTPIN (300 400) $PN DY38
J 2
(290 410);
DISPLAY 0.680851 (290 410);
PAINT MONO (290 410);
FORCEPROP 0 LASTPIN (300 450) $PN EA37
J 2
(290 460);
DISPLAY 0.680851 (290 460);
PAINT MONO (290 460);
FORCEPROP 0 LASTPIN (2750 900) $PN EB42
J 0
(2760 910);
DISPLAY 0.680851 (2760 910);
PAINT MONO (2760 910);
FORCEPROP 0 LASTPIN (2750 600) $PN DN54
J 0
(2760 610);
DISPLAY 0.680851 (2760 610);
PAINT MONO (2760 610);
FORCEPROP 0 LASTPIN (2750 650) $PN DP53
J 0
(2760 660);
DISPLAY 0.680851 (2760 660);
PAINT MONO (2760 660);
FORCEPROP 0 LASTPIN (2750 700) $PN DL54
J 0
(2760 710);
DISPLAY 0.680851 (2760 710);
PAINT MONO (2760 710);
FORCEPROP 0 LASTPIN (2750 750) $PN DK53
J 0
(2760 760);
DISPLAY 0.680851 (2760 760);
PAINT MONO (2760 760);
FORCEPROP 0 LASTPIN (2750 300) $PN EA41
J 0
(2760 310);
DISPLAY 0.680851 (2760 310);
PAINT MONO (2760 310);
FORCEPROP 0 LASTPIN (2750 350) $PN DY40
J 0
(2760 360);
DISPLAY 0.680851 (2760 360);
PAINT MONO (2760 360);
FORCEPROP 0 LASTPIN (2750 400) $PN DU41
J 0
(2760 410);
DISPLAY 0.680851 (2760 410);
PAINT MONO (2760 410);
FORCEPROP 0 LASTPIN (2750 450) $PN DV40
J 0
(2760 460);
DISPLAY 0.680851 (2760 460);
PAINT MONO (2760 460);
FORCEPROP 2 LAST CDS_LIB pure_quanta
J 0
(1525 1950);
DISPLAY INVISIBLE (1525 1950);
FORCEPROP 1 LAST NEEDS_NO_SIZE TRUE
J 0
(1525 1950);
DISPLAY 0.723404 (1525 1950);
PAINT GREEN (1525 1950);
DISPLAY INVISIBLE (1525 1950);
FORCEPROP 1 LAST CDS_LMAN_SYM_OUTLINE -1100,2250,1050,-2250
J 0
(1525 1950);
DISPLAY 0.468085 (1525 1950);
PAINT GREEN (1525 1950);
DISPLAY INVISIBLE (1525 1950);
FORCEPROP 2 LAST CDS_LOCATION U2
J 0
(425 4525);
DISPLAY 1.021277 (425 4525);
DISPLAY INVISIBLE (425 4525);
FORCEPROP 0 LAST $SEC 14
J 0
(425 4525);
DISPLAY 0.680851 (425 4525);
PAINT MONO (425 4525);
DISPLAY INVISIBLE (425 4525);
FORCEPROP 2 LAST CDS_SEC 14
J 0
(425 4525);
DISPLAY 1.021277 (425 4525);
DISPLAY INVISIBLE (425 4525);
FORCEPROP 1 LAST PATH I169
J 0
(1525 1950);
DISPLAY 0.723404 (1525 1950);
PAINT GREEN (1525 1950);
DISPLAY INVISIBLE (1525 1950);
FORCEADD TAP..1
R 2
(-200 450);
FORCEPROP 3 LASTPIN (-150 450) SIG_NAME M_G_CPU0_SB_CB<7>
J 0
(-140 460);
DISPLAY 0.659574 (-140 460);
PAINT MONO (-140 460);
DISPLAY INVISIBLE (-140 460);
FORCEPROP 1 LASTPIN (-150 450) BN 7
J 2
(-138 458);
DISPLAY 0.680851 (-138 458);
PAINT GREEN (-138 458);
FORCEPROP 2 LAST CDS_LIB standard
J 0
(-200 450);
DISPLAY INVISIBLE (-200 450);
FORCEPROP 1 LAST BODY_TYPE PLUMBING
J 2
(-200 500);
DISPLAY 0.872340 (-200 500);
PAINT GREEN (-200 500);
DISPLAY INVISIBLE (-200 500);
FORCEPROP 1 LAST HDL_TAP TRUE
J 2
(-525 325);
DISPLAY 0.872340 (-525 325);
DISPLAY INVISIBLE (-525 325);
FORCEPROP 1 LAST PATH I17
J 2
(-198 450);
DISPLAY 0.872340 (-198 450);
PAINT GREEN (-198 450);
DISPLAY INVISIBLE (-198 450);
FORCEADD TAP..1
R 2
(-200 550);
FORCEPROP 3 LASTPIN (-150 550) SIG_NAME M_G_CPU0_SB_DQ<1>
J 0
(-140 560);
DISPLAY 0.659574 (-140 560);
PAINT MONO (-140 560);
DISPLAY INVISIBLE (-140 560);
FORCEPROP 1 LASTPIN (-150 550) BN 1
J 2
(-138 558);
DISPLAY 0.680851 (-138 558);
PAINT GREEN (-138 558);
FORCEPROP 2 LAST CDS_LIB standard
J 0
(-200 550);
DISPLAY INVISIBLE (-200 550);
FORCEPROP 1 LAST BODY_TYPE PLUMBING
J 2
(-200 600);
DISPLAY 0.872340 (-200 600);
PAINT GREEN (-200 600);
DISPLAY INVISIBLE (-200 600);
FORCEPROP 1 LAST HDL_TAP TRUE
J 2
(-525 425);
DISPLAY 0.872340 (-525 425);
DISPLAY INVISIBLE (-525 425);
FORCEPROP 1 LAST PATH I18
J 2
(-198 550);
DISPLAY 0.872340 (-198 550);
PAINT GREEN (-198 550);
DISPLAY INVISIBLE (-198 550);
FORCEADD TAP..1
R 2
(-200 650);
FORCEPROP 3 LASTPIN (-150 650) SIG_NAME M_G_CPU0_SB_DQ<3>
J 0
(-140 660);
DISPLAY 0.659574 (-140 660);
PAINT MONO (-140 660);
DISPLAY INVISIBLE (-140 660);
FORCEPROP 1 LASTPIN (-150 650) BN 3
J 2
(-138 658);
DISPLAY 0.680851 (-138 658);
PAINT GREEN (-138 658);
FORCEPROP 2 LAST CDS_LIB standard
J 0
(-200 650);
DISPLAY INVISIBLE (-200 650);
FORCEPROP 1 LAST BODY_TYPE PLUMBING
J 2
(-200 700);
DISPLAY 0.872340 (-200 700);
PAINT GREEN (-200 700);
DISPLAY INVISIBLE (-200 700);
FORCEPROP 1 LAST HDL_TAP TRUE
J 2
(-525 525);
DISPLAY 0.872340 (-525 525);
DISPLAY INVISIBLE (-525 525);
FORCEPROP 1 LAST PATH I19
J 2
(-198 650);
DISPLAY 0.872340 (-198 650);
PAINT GREEN (-198 650);
DISPLAY INVISIBLE (-198 650);
FORCEADD OFFPAGE..2
R 2
(-1225 -75);
FORCEPROP 2 LAST $XR1 95 
J 0
(-1569 -75);
DISPLAY 0.638298 (-1569 -75);
PAINT MONO (-1569 -75);
FORCEPROP 2 LAST $XR0 94 
J 0
(-1479 -75);
DISPLAY 0.638298 (-1479 -75);
PAINT MONO (-1479 -75);
FORCEPROP 2 LAST CDS_LIB standard
J 0
(-1225 -75);
PAINT MONO (-1225 -75);
DISPLAY INVISIBLE (-1225 -75);
FORCEPROP 1 LAST OFFPAGE TRUE
J 2
(-1550 -200);
DISPLAY 0.872340 (-1550 -200);
DISPLAY INVISIBLE (-1550 -200);
FORCEPROP 1 LAST COMMENT_BODY TRUE
J 2
(-1180 -170);
DISPLAY 0.872340 (-1180 -170);
PAINT GREEN (-1180 -170);
DISPLAY INVISIBLE (-1180 -170);
FORCEPROP 2 LAST PATH I2
J 0
(-1175 0);
DISPLAY 1.021277 (-1175 0);
DISPLAY INVISIBLE (-1175 0);
FORCEADD TAP..1
R 2
(-200 600);
FORCEPROP 3 LASTPIN (-150 600) SIG_NAME M_G_CPU0_SB_DQ<2>
J 0
(-140 610);
DISPLAY 0.659574 (-140 610);
PAINT MONO (-140 610);
DISPLAY INVISIBLE (-140 610);
FORCEPROP 1 LASTPIN (-150 600) BN 2
J 2
(-138 608);
DISPLAY 0.680851 (-138 608);
PAINT GREEN (-138 608);
FORCEPROP 2 LAST CDS_LIB standard
J 0
(-200 600);
DISPLAY INVISIBLE (-200 600);
FORCEPROP 1 LAST BODY_TYPE PLUMBING
J 2
(-200 650);
DISPLAY 0.872340 (-200 650);
PAINT GREEN (-200 650);
DISPLAY INVISIBLE (-200 650);
FORCEPROP 1 LAST HDL_TAP TRUE
J 2
(-525 475);
DISPLAY 0.872340 (-525 475);
DISPLAY INVISIBLE (-525 475);
FORCEPROP 1 LAST PATH I20
J 2
(-198 600);
DISPLAY 0.872340 (-198 600);
PAINT GREEN (-198 600);
DISPLAY INVISIBLE (-198 600);
FORCEADD TAP..1
R 2
(-200 700);
FORCEPROP 3 LASTPIN (-150 700) SIG_NAME M_G_CPU0_SB_DQ<4>
J 0
(-140 710);
DISPLAY 0.659574 (-140 710);
PAINT MONO (-140 710);
DISPLAY INVISIBLE (-140 710);
FORCEPROP 1 LASTPIN (-150 700) BN 4
J 2
(-138 708);
DISPLAY 0.680851 (-138 708);
PAINT GREEN (-138 708);
FORCEPROP 2 LAST CDS_LIB standard
J 0
(-200 700);
DISPLAY INVISIBLE (-200 700);
FORCEPROP 1 LAST BODY_TYPE PLUMBING
J 2
(-200 750);
DISPLAY 0.872340 (-200 750);
PAINT GREEN (-200 750);
DISPLAY INVISIBLE (-200 750);
FORCEPROP 1 LAST HDL_TAP TRUE
J 2
(-525 575);
DISPLAY 0.872340 (-525 575);
DISPLAY INVISIBLE (-525 575);
FORCEPROP 1 LAST PATH I21
J 2
(-198 700);
DISPLAY 0.872340 (-198 700);
PAINT GREEN (-198 700);
DISPLAY INVISIBLE (-198 700);
FORCEADD TAP..1
R 2
(-200 800);
FORCEPROP 3 LASTPIN (-150 800) SIG_NAME M_G_CPU0_SB_DQ<6>
J 0
(-140 810);
DISPLAY 0.659574 (-140 810);
PAINT MONO (-140 810);
DISPLAY INVISIBLE (-140 810);
FORCEPROP 1 LASTPIN (-150 800) BN 6
J 2
(-138 808);
DISPLAY 0.680851 (-138 808);
PAINT GREEN (-138 808);
FORCEPROP 2 LAST CDS_LIB standard
J 0
(-200 800);
DISPLAY INVISIBLE (-200 800);
FORCEPROP 1 LAST BODY_TYPE PLUMBING
J 2
(-200 850);
DISPLAY 0.872340 (-200 850);
PAINT GREEN (-200 850);
DISPLAY INVISIBLE (-200 850);
FORCEPROP 1 LAST HDL_TAP TRUE
J 2
(-525 675);
DISPLAY 0.872340 (-525 675);
DISPLAY INVISIBLE (-525 675);
FORCEPROP 1 LAST PATH I22
J 2
(-198 800);
DISPLAY 0.872340 (-198 800);
PAINT GREEN (-198 800);
DISPLAY INVISIBLE (-198 800);
FORCEADD TAP..1
R 2
(-200 750);
FORCEPROP 3 LASTPIN (-150 750) SIG_NAME M_G_CPU0_SB_DQ<5>
J 0
(-140 760);
DISPLAY 0.659574 (-140 760);
PAINT MONO (-140 760);
DISPLAY INVISIBLE (-140 760);
FORCEPROP 1 LASTPIN (-150 750) BN 5
J 2
(-138 758);
DISPLAY 0.680851 (-138 758);
PAINT GREEN (-138 758);
FORCEPROP 2 LAST CDS_LIB standard
J 0
(-200 750);
DISPLAY INVISIBLE (-200 750);
FORCEPROP 1 LAST BODY_TYPE PLUMBING
J 2
(-200 800);
DISPLAY 0.872340 (-200 800);
PAINT GREEN (-200 800);
DISPLAY INVISIBLE (-200 800);
FORCEPROP 1 LAST HDL_TAP TRUE
J 2
(-525 625);
DISPLAY 0.872340 (-525 625);
DISPLAY INVISIBLE (-525 625);
FORCEPROP 1 LAST PATH I23
J 2
(-198 750);
DISPLAY 0.872340 (-198 750);
PAINT GREEN (-198 750);
DISPLAY INVISIBLE (-198 750);
FORCEADD TAP..1
R 2
(-200 900);
FORCEPROP 3 LASTPIN (-150 900) SIG_NAME M_G_CPU0_SB_DQ<8>
J 0
(-140 910);
DISPLAY 0.659574 (-140 910);
PAINT MONO (-140 910);
DISPLAY INVISIBLE (-140 910);
FORCEPROP 1 LASTPIN (-150 900) BN 8
J 2
(-138 908);
DISPLAY 0.680851 (-138 908);
PAINT GREEN (-138 908);
FORCEPROP 2 LAST CDS_LIB standard
J 0
(-200 900);
DISPLAY INVISIBLE (-200 900);
FORCEPROP 1 LAST BODY_TYPE PLUMBING
J 2
(-200 950);
DISPLAY 0.872340 (-200 950);
PAINT GREEN (-200 950);
DISPLAY INVISIBLE (-200 950);
FORCEPROP 1 LAST HDL_TAP TRUE
J 2
(-525 775);
DISPLAY 0.872340 (-525 775);
DISPLAY INVISIBLE (-525 775);
FORCEPROP 1 LAST PATH I24
J 2
(-198 900);
DISPLAY 0.872340 (-198 900);
PAINT GREEN (-198 900);
DISPLAY INVISIBLE (-198 900);
FORCEADD TAP..1
R 2
(-200 850);
FORCEPROP 3 LASTPIN (-150 850) SIG_NAME M_G_CPU0_SB_DQ<7>
J 0
(-140 860);
DISPLAY 0.659574 (-140 860);
PAINT MONO (-140 860);
DISPLAY INVISIBLE (-140 860);
FORCEPROP 1 LASTPIN (-150 850) BN 7
J 2
(-138 858);
DISPLAY 0.680851 (-138 858);
PAINT GREEN (-138 858);
FORCEPROP 2 LAST CDS_LIB standard
J 0
(-200 850);
DISPLAY INVISIBLE (-200 850);
FORCEPROP 1 LAST BODY_TYPE PLUMBING
J 2
(-200 900);
DISPLAY 0.872340 (-200 900);
PAINT GREEN (-200 900);
DISPLAY INVISIBLE (-200 900);
FORCEPROP 1 LAST HDL_TAP TRUE
J 2
(-525 725);
DISPLAY 0.872340 (-525 725);
DISPLAY INVISIBLE (-525 725);
FORCEPROP 1 LAST PATH I25
J 2
(-198 850);
DISPLAY 0.872340 (-198 850);
PAINT GREEN (-198 850);
DISPLAY INVISIBLE (-198 850);
FORCEADD TAP..1
R 2
(-200 950);
FORCEPROP 3 LASTPIN (-150 950) SIG_NAME M_G_CPU0_SB_DQ<9>
J 0
(-140 960);
DISPLAY 0.659574 (-140 960);
PAINT MONO (-140 960);
DISPLAY INVISIBLE (-140 960);
FORCEPROP 1 LASTPIN (-150 950) BN 9
J 2
(-138 958);
DISPLAY 0.680851 (-138 958);
PAINT GREEN (-138 958);
FORCEPROP 2 LAST CDS_LIB standard
J 0
(-200 950);
DISPLAY INVISIBLE (-200 950);
FORCEPROP 1 LAST BODY_TYPE PLUMBING
J 2
(-200 1000);
DISPLAY 0.872340 (-200 1000);
PAINT GREEN (-200 1000);
DISPLAY INVISIBLE (-200 1000);
FORCEPROP 1 LAST HDL_TAP TRUE
J 2
(-525 825);
DISPLAY 0.872340 (-525 825);
DISPLAY INVISIBLE (-525 825);
FORCEPROP 1 LAST PATH I26
J 2
(-198 950);
DISPLAY 0.872340 (-198 950);
PAINT GREEN (-198 950);
DISPLAY INVISIBLE (-198 950);
FORCEADD TAP..1
R 2
(-200 1000);
FORCEPROP 3 LASTPIN (-150 1000) SIG_NAME M_G_CPU0_SB_DQ<10>
J 0
(-140 1010);
DISPLAY 0.659574 (-140 1010);
PAINT MONO (-140 1010);
DISPLAY INVISIBLE (-140 1010);
FORCEPROP 1 LASTPIN (-150 1000) BN 10
J 2
(-138 1008);
DISPLAY 0.680851 (-138 1008);
PAINT GREEN (-138 1008);
FORCEPROP 2 LAST CDS_LIB standard
J 0
(-200 1000);
DISPLAY INVISIBLE (-200 1000);
FORCEPROP 1 LAST BODY_TYPE PLUMBING
J 2
(-200 1050);
DISPLAY 0.872340 (-200 1050);
PAINT GREEN (-200 1050);
DISPLAY INVISIBLE (-200 1050);
FORCEPROP 1 LAST HDL_TAP TRUE
J 2
(-525 875);
DISPLAY 0.872340 (-525 875);
DISPLAY INVISIBLE (-525 875);
FORCEPROP 1 LAST PATH I27
J 2
(-198 1000);
DISPLAY 0.872340 (-198 1000);
PAINT GREEN (-198 1000);
DISPLAY INVISIBLE (-198 1000);
FORCEADD TAP..1
R 2
(-200 1050);
FORCEPROP 3 LASTPIN (-150 1050) SIG_NAME M_G_CPU0_SB_DQ<11>
J 0
(-140 1060);
DISPLAY 0.659574 (-140 1060);
PAINT MONO (-140 1060);
DISPLAY INVISIBLE (-140 1060);
FORCEPROP 1 LASTPIN (-150 1050) BN 11
J 2
(-138 1058);
DISPLAY 0.680851 (-138 1058);
PAINT GREEN (-138 1058);
FORCEPROP 2 LAST CDS_LIB standard
J 0
(-200 1050);
DISPLAY INVISIBLE (-200 1050);
FORCEPROP 1 LAST BODY_TYPE PLUMBING
J 2
(-200 1100);
DISPLAY 0.872340 (-200 1100);
PAINT GREEN (-200 1100);
DISPLAY INVISIBLE (-200 1100);
FORCEPROP 1 LAST HDL_TAP TRUE
J 2
(-525 925);
DISPLAY 0.872340 (-525 925);
DISPLAY INVISIBLE (-525 925);
FORCEPROP 1 LAST PATH I28
J 2
(-198 1050);
DISPLAY 0.872340 (-198 1050);
PAINT GREEN (-198 1050);
DISPLAY INVISIBLE (-198 1050);
FORCEADD TAP..1
R 2
(-200 1150);
FORCEPROP 3 LASTPIN (-150 1150) SIG_NAME M_G_CPU0_SB_DQ<13>
J 0
(-140 1160);
DISPLAY 0.659574 (-140 1160);
PAINT MONO (-140 1160);
DISPLAY INVISIBLE (-140 1160);
FORCEPROP 1 LASTPIN (-150 1150) BN 13
J 2
(-138 1158);
DISPLAY 0.680851 (-138 1158);
PAINT GREEN (-138 1158);
FORCEPROP 2 LAST CDS_LIB standard
J 0
(-200 1150);
DISPLAY INVISIBLE (-200 1150);
FORCEPROP 1 LAST BODY_TYPE PLUMBING
J 2
(-200 1200);
DISPLAY 0.872340 (-200 1200);
PAINT GREEN (-200 1200);
DISPLAY INVISIBLE (-200 1200);
FORCEPROP 1 LAST HDL_TAP TRUE
J 2
(-525 1025);
DISPLAY 0.872340 (-525 1025);
DISPLAY INVISIBLE (-525 1025);
FORCEPROP 1 LAST PATH I29
J 2
(-198 1150);
DISPLAY 0.872340 (-198 1150);
PAINT GREEN (-198 1150);
DISPLAY INVISIBLE (-198 1150);
FORCEADD TAP..1
R 2
(-200 -100);
FORCEPROP 3 LASTPIN (-150 -100) SIG_NAME M_G_CPU0_CLK_DN<1>
J 0
(-140 -90);
DISPLAY 0.659574 (-140 -90);
PAINT MONO (-140 -90);
DISPLAY INVISIBLE (-140 -90);
FORCEPROP 1 LASTPIN (-150 -100) BN 1
J 2
(-138 -92);
DISPLAY 0.680851 (-138 -92);
PAINT GREEN (-138 -92);
FORCEPROP 2 LAST CDS_LIB standard
J 0
(-200 -100);
DISPLAY INVISIBLE (-200 -100);
FORCEPROP 1 LAST BODY_TYPE PLUMBING
J 2
(-200 -50);
DISPLAY 0.872340 (-200 -50);
PAINT GREEN (-200 -50);
DISPLAY INVISIBLE (-200 -50);
FORCEPROP 1 LAST HDL_TAP TRUE
J 2
(-525 -225);
DISPLAY 0.872340 (-525 -225);
DISPLAY INVISIBLE (-525 -225);
FORCEPROP 1 LAST PATH I3
J 2
(-198 -100);
DISPLAY 0.872340 (-198 -100);
PAINT GREEN (-198 -100);
DISPLAY INVISIBLE (-198 -100);
FORCEADD TAP..1
R 2
(-200 1100);
FORCEPROP 3 LASTPIN (-150 1100) SIG_NAME M_G_CPU0_SB_DQ<12>
J 0
(-140 1110);
DISPLAY 0.659574 (-140 1110);
PAINT MONO (-140 1110);
DISPLAY INVISIBLE (-140 1110);
FORCEPROP 1 LASTPIN (-150 1100) BN 12
J 2
(-138 1108);
DISPLAY 0.680851 (-138 1108);
PAINT GREEN (-138 1108);
FORCEPROP 2 LAST CDS_LIB standard
J 0
(-200 1100);
DISPLAY INVISIBLE (-200 1100);
FORCEPROP 1 LAST BODY_TYPE PLUMBING
J 2
(-200 1150);
DISPLAY 0.872340 (-200 1150);
PAINT GREEN (-200 1150);
DISPLAY INVISIBLE (-200 1150);
FORCEPROP 1 LAST HDL_TAP TRUE
J 2
(-525 975);
DISPLAY 0.872340 (-525 975);
DISPLAY INVISIBLE (-525 975);
FORCEPROP 1 LAST PATH I30
J 2
(-198 1100);
DISPLAY 0.872340 (-198 1100);
PAINT GREEN (-198 1100);
DISPLAY INVISIBLE (-198 1100);
FORCEADD TAP..1
R 2
(-200 1200);
FORCEPROP 3 LASTPIN (-150 1200) SIG_NAME M_G_CPU0_SB_DQ<14>
J 0
(-140 1210);
DISPLAY 0.659574 (-140 1210);
PAINT MONO (-140 1210);
DISPLAY INVISIBLE (-140 1210);
FORCEPROP 1 LASTPIN (-150 1200) BN 14
J 2
(-138 1208);
DISPLAY 0.680851 (-138 1208);
PAINT GREEN (-138 1208);
FORCEPROP 2 LAST CDS_LIB standard
J 0
(-200 1200);
DISPLAY INVISIBLE (-200 1200);
FORCEPROP 1 LAST BODY_TYPE PLUMBING
J 2
(-200 1250);
DISPLAY 0.872340 (-200 1250);
PAINT GREEN (-200 1250);
DISPLAY INVISIBLE (-200 1250);
FORCEPROP 1 LAST HDL_TAP TRUE
J 2
(-525 1075);
DISPLAY 0.872340 (-525 1075);
DISPLAY INVISIBLE (-525 1075);
FORCEPROP 1 LAST PATH I31
J 2
(-198 1200);
DISPLAY 0.872340 (-198 1200);
PAINT GREEN (-198 1200);
DISPLAY INVISIBLE (-198 1200);
FORCEADD TAP..1
R 2
(-200 1250);
FORCEPROP 3 LASTPIN (-150 1250) SIG_NAME M_G_CPU0_SB_DQ<15>
J 0
(-140 1260);
DISPLAY 0.659574 (-140 1260);
PAINT MONO (-140 1260);
DISPLAY INVISIBLE (-140 1260);
FORCEPROP 1 LASTPIN (-150 1250) BN 15
J 2
(-138 1258);
DISPLAY 0.680851 (-138 1258);
PAINT GREEN (-138 1258);
FORCEPROP 2 LAST CDS_LIB standard
J 0
(-200 1250);
DISPLAY INVISIBLE (-200 1250);
FORCEPROP 1 LAST BODY_TYPE PLUMBING
J 2
(-200 1300);
DISPLAY 0.872340 (-200 1300);
PAINT GREEN (-200 1300);
DISPLAY INVISIBLE (-200 1300);
FORCEPROP 1 LAST HDL_TAP TRUE
J 2
(-525 1125);
DISPLAY 0.872340 (-525 1125);
DISPLAY INVISIBLE (-525 1125);
FORCEPROP 1 LAST PATH I32
J 2
(-198 1250);
DISPLAY 0.872340 (-198 1250);
PAINT GREEN (-198 1250);
DISPLAY INVISIBLE (-198 1250);
FORCEADD TAP..1
R 2
(-200 1300);
FORCEPROP 3 LASTPIN (-150 1300) SIG_NAME M_G_CPU0_SB_DQ<16>
J 0
(-140 1310);
DISPLAY 0.659574 (-140 1310);
PAINT MONO (-140 1310);
DISPLAY INVISIBLE (-140 1310);
FORCEPROP 1 LASTPIN (-150 1300) BN 16
J 2
(-138 1308);
DISPLAY 0.680851 (-138 1308);
PAINT GREEN (-138 1308);
FORCEPROP 2 LAST CDS_LIB standard
J 0
(-200 1300);
DISPLAY INVISIBLE (-200 1300);
FORCEPROP 1 LAST BODY_TYPE PLUMBING
J 2
(-200 1350);
DISPLAY 0.872340 (-200 1350);
PAINT GREEN (-200 1350);
DISPLAY INVISIBLE (-200 1350);
FORCEPROP 1 LAST HDL_TAP TRUE
J 2
(-525 1175);
DISPLAY 0.872340 (-525 1175);
DISPLAY INVISIBLE (-525 1175);
FORCEPROP 1 LAST PATH I33
J 2
(-198 1300);
DISPLAY 0.872340 (-198 1300);
PAINT GREEN (-198 1300);
DISPLAY INVISIBLE (-198 1300);
FORCEADD TAP..1
R 2
(-200 1400);
FORCEPROP 3 LASTPIN (-150 1400) SIG_NAME M_G_CPU0_SB_DQ<18>
J 0
(-140 1410);
DISPLAY 0.659574 (-140 1410);
PAINT MONO (-140 1410);
DISPLAY INVISIBLE (-140 1410);
FORCEPROP 1 LASTPIN (-150 1400) BN 18
J 2
(-138 1408);
DISPLAY 0.680851 (-138 1408);
PAINT GREEN (-138 1408);
FORCEPROP 2 LAST CDS_LIB standard
J 0
(-200 1400);
DISPLAY INVISIBLE (-200 1400);
FORCEPROP 1 LAST BODY_TYPE PLUMBING
J 2
(-200 1450);
DISPLAY 0.872340 (-200 1450);
PAINT GREEN (-200 1450);
DISPLAY INVISIBLE (-200 1450);
FORCEPROP 1 LAST HDL_TAP TRUE
J 2
(-525 1275);
DISPLAY 0.872340 (-525 1275);
DISPLAY INVISIBLE (-525 1275);
FORCEPROP 1 LAST PATH I34
J 2
(-198 1400);
DISPLAY 0.872340 (-198 1400);
PAINT GREEN (-198 1400);
DISPLAY INVISIBLE (-198 1400);
FORCEADD TAP..1
R 2
(-200 1450);
FORCEPROP 3 LASTPIN (-150 1450) SIG_NAME M_G_CPU0_SB_DQ<19>
J 0
(-140 1460);
DISPLAY 0.659574 (-140 1460);
PAINT MONO (-140 1460);
DISPLAY INVISIBLE (-140 1460);
FORCEPROP 1 LASTPIN (-150 1450) BN 19
J 2
(-138 1458);
DISPLAY 0.680851 (-138 1458);
PAINT GREEN (-138 1458);
FORCEPROP 2 LAST CDS_LIB standard
J 0
(-200 1450);
DISPLAY INVISIBLE (-200 1450);
FORCEPROP 1 LAST BODY_TYPE PLUMBING
J 2
(-200 1500);
DISPLAY 0.872340 (-200 1500);
PAINT GREEN (-200 1500);
DISPLAY INVISIBLE (-200 1500);
FORCEPROP 1 LAST HDL_TAP TRUE
J 2
(-525 1325);
DISPLAY 0.872340 (-525 1325);
DISPLAY INVISIBLE (-525 1325);
FORCEPROP 1 LAST PATH I35
J 2
(-198 1450);
DISPLAY 0.872340 (-198 1450);
PAINT GREEN (-198 1450);
DISPLAY INVISIBLE (-198 1450);
FORCEADD TAP..1
R 2
(-200 1350);
FORCEPROP 3 LASTPIN (-150 1350) SIG_NAME M_G_CPU0_SB_DQ<17>
J 0
(-140 1360);
DISPLAY 0.659574 (-140 1360);
PAINT MONO (-140 1360);
DISPLAY INVISIBLE (-140 1360);
FORCEPROP 1 LASTPIN (-150 1350) BN 17
J 2
(-138 1358);
DISPLAY 0.680851 (-138 1358);
PAINT GREEN (-138 1358);
FORCEPROP 2 LAST CDS_LIB standard
J 0
(-200 1350);
DISPLAY INVISIBLE (-200 1350);
FORCEPROP 1 LAST BODY_TYPE PLUMBING
J 2
(-200 1400);
DISPLAY 0.872340 (-200 1400);
PAINT GREEN (-200 1400);
DISPLAY INVISIBLE (-200 1400);
FORCEPROP 1 LAST HDL_TAP TRUE
J 2
(-525 1225);
DISPLAY 0.872340 (-525 1225);
DISPLAY INVISIBLE (-525 1225);
FORCEPROP 1 LAST PATH I36
J 2
(-198 1350);
DISPLAY 0.872340 (-198 1350);
PAINT GREEN (-198 1350);
DISPLAY INVISIBLE (-198 1350);
FORCEADD TAP..1
R 2
(-200 1550);
FORCEPROP 3 LASTPIN (-150 1550) SIG_NAME M_G_CPU0_SB_DQ<21>
J 0
(-140 1560);
DISPLAY 0.659574 (-140 1560);
PAINT MONO (-140 1560);
DISPLAY INVISIBLE (-140 1560);
FORCEPROP 1 LASTPIN (-150 1550) BN 21
J 2
(-138 1558);
DISPLAY 0.680851 (-138 1558);
PAINT GREEN (-138 1558);
FORCEPROP 2 LAST CDS_LIB standard
J 0
(-200 1550);
DISPLAY INVISIBLE (-200 1550);
FORCEPROP 1 LAST BODY_TYPE PLUMBING
J 2
(-200 1600);
DISPLAY 0.872340 (-200 1600);
PAINT GREEN (-200 1600);
DISPLAY INVISIBLE (-200 1600);
FORCEPROP 1 LAST HDL_TAP TRUE
J 2
(-525 1425);
DISPLAY 0.872340 (-525 1425);
DISPLAY INVISIBLE (-525 1425);
FORCEPROP 1 LAST PATH I37
J 2
(-198 1550);
DISPLAY 0.872340 (-198 1550);
PAINT GREEN (-198 1550);
DISPLAY INVISIBLE (-198 1550);
FORCEADD TAP..1
R 2
(-200 1500);
FORCEPROP 3 LASTPIN (-150 1500) SIG_NAME M_G_CPU0_SB_DQ<20>
J 0
(-140 1510);
DISPLAY 0.659574 (-140 1510);
PAINT MONO (-140 1510);
DISPLAY INVISIBLE (-140 1510);
FORCEPROP 1 LASTPIN (-150 1500) BN 20
J 2
(-138 1508);
DISPLAY 0.680851 (-138 1508);
PAINT GREEN (-138 1508);
FORCEPROP 2 LAST CDS_LIB standard
J 0
(-200 1500);
DISPLAY INVISIBLE (-200 1500);
FORCEPROP 1 LAST BODY_TYPE PLUMBING
J 2
(-200 1550);
DISPLAY 0.872340 (-200 1550);
PAINT GREEN (-200 1550);
DISPLAY INVISIBLE (-200 1550);
FORCEPROP 1 LAST HDL_TAP TRUE
J 2
(-525 1375);
DISPLAY 0.872340 (-525 1375);
DISPLAY INVISIBLE (-525 1375);
FORCEPROP 1 LAST PATH I38
J 2
(-198 1500);
DISPLAY 0.872340 (-198 1500);
PAINT GREEN (-198 1500);
DISPLAY INVISIBLE (-198 1500);
FORCEADD TAP..1
R 2
(-200 1600);
FORCEPROP 3 LASTPIN (-150 1600) SIG_NAME M_G_CPU0_SB_DQ<22>
J 0
(-140 1610);
DISPLAY 0.659574 (-140 1610);
PAINT MONO (-140 1610);
DISPLAY INVISIBLE (-140 1610);
FORCEPROP 1 LASTPIN (-150 1600) BN 22
J 2
(-138 1608);
DISPLAY 0.680851 (-138 1608);
PAINT GREEN (-138 1608);
FORCEPROP 2 LAST CDS_LIB standard
J 0
(-200 1600);
DISPLAY INVISIBLE (-200 1600);
FORCEPROP 1 LAST BODY_TYPE PLUMBING
J 2
(-200 1650);
DISPLAY 0.872340 (-200 1650);
PAINT GREEN (-200 1650);
DISPLAY INVISIBLE (-200 1650);
FORCEPROP 1 LAST HDL_TAP TRUE
J 2
(-525 1475);
DISPLAY 0.872340 (-525 1475);
DISPLAY INVISIBLE (-525 1475);
FORCEPROP 1 LAST PATH I39
J 2
(-198 1600);
DISPLAY 0.872340 (-198 1600);
PAINT GREEN (-198 1600);
DISPLAY INVISIBLE (-198 1600);
FORCEADD TAP..1
R 2
(-200 -150);
FORCEPROP 3 LASTPIN (-150 -150) SIG_NAME M_G_CPU0_CLK_DN<0>
J 0
(-140 -140);
DISPLAY 0.659574 (-140 -140);
PAINT MONO (-140 -140);
DISPLAY INVISIBLE (-140 -140);
FORCEPROP 1 LASTPIN (-150 -150) BN 0
J 2
(-138 -142);
DISPLAY 0.680851 (-138 -142);
PAINT GREEN (-138 -142);
FORCEPROP 2 LAST CDS_LIB standard
J 0
(-200 -150);
DISPLAY INVISIBLE (-200 -150);
FORCEPROP 1 LAST BODY_TYPE PLUMBING
J 2
(-200 -100);
DISPLAY 0.872340 (-200 -100);
PAINT GREEN (-200 -100);
DISPLAY INVISIBLE (-200 -100);
FORCEPROP 1 LAST HDL_TAP TRUE
J 2
(-525 -275);
DISPLAY 0.872340 (-525 -275);
DISPLAY INVISIBLE (-525 -275);
FORCEPROP 1 LAST PATH I4
J 2
(-198 -150);
DISPLAY 0.872340 (-198 -150);
PAINT GREEN (-198 -150);
DISPLAY INVISIBLE (-198 -150);
FORCEADD TAP..1
R 2
(-200 1650);
FORCEPROP 3 LASTPIN (-150 1650) SIG_NAME M_G_CPU0_SB_DQ<23>
J 0
(-140 1660);
DISPLAY 0.659574 (-140 1660);
PAINT MONO (-140 1660);
DISPLAY INVISIBLE (-140 1660);
FORCEPROP 1 LASTPIN (-150 1650) BN 23
J 2
(-138 1658);
DISPLAY 0.680851 (-138 1658);
PAINT GREEN (-138 1658);
FORCEPROP 2 LAST CDS_LIB standard
J 0
(-200 1650);
DISPLAY INVISIBLE (-200 1650);
FORCEPROP 1 LAST BODY_TYPE PLUMBING
J 2
(-200 1700);
DISPLAY 0.872340 (-200 1700);
PAINT GREEN (-200 1700);
DISPLAY INVISIBLE (-200 1700);
FORCEPROP 1 LAST HDL_TAP TRUE
J 2
(-525 1525);
DISPLAY 0.872340 (-525 1525);
DISPLAY INVISIBLE (-525 1525);
FORCEPROP 1 LAST PATH I40
J 2
(-198 1650);
DISPLAY 0.872340 (-198 1650);
PAINT GREEN (-198 1650);
DISPLAY INVISIBLE (-198 1650);
FORCEADD TAP..1
R 2
(-200 1700);
FORCEPROP 3 LASTPIN (-150 1700) SIG_NAME M_G_CPU0_SB_DQ<24>
J 0
(-140 1710);
DISPLAY 0.659574 (-140 1710);
PAINT MONO (-140 1710);
DISPLAY INVISIBLE (-140 1710);
FORCEPROP 1 LASTPIN (-150 1700) BN 24
J 2
(-138 1708);
DISPLAY 0.680851 (-138 1708);
PAINT GREEN (-138 1708);
FORCEPROP 2 LAST CDS_LIB standard
J 0
(-200 1700);
DISPLAY INVISIBLE (-200 1700);
FORCEPROP 1 LAST BODY_TYPE PLUMBING
J 2
(-200 1750);
DISPLAY 0.872340 (-200 1750);
PAINT GREEN (-200 1750);
DISPLAY INVISIBLE (-200 1750);
FORCEPROP 1 LAST HDL_TAP TRUE
J 2
(-525 1575);
DISPLAY 0.872340 (-525 1575);
DISPLAY INVISIBLE (-525 1575);
FORCEPROP 1 LAST PATH I41
J 2
(-198 1700);
DISPLAY 0.872340 (-198 1700);
PAINT GREEN (-198 1700);
DISPLAY INVISIBLE (-198 1700);
FORCEADD TAP..1
R 2
(-200 1750);
FORCEPROP 3 LASTPIN (-150 1750) SIG_NAME M_G_CPU0_SB_DQ<25>
J 0
(-140 1760);
DISPLAY 0.659574 (-140 1760);
PAINT MONO (-140 1760);
DISPLAY INVISIBLE (-140 1760);
FORCEPROP 1 LASTPIN (-150 1750) BN 25
J 2
(-138 1758);
DISPLAY 0.680851 (-138 1758);
PAINT GREEN (-138 1758);
FORCEPROP 2 LAST CDS_LIB standard
J 0
(-200 1750);
DISPLAY INVISIBLE (-200 1750);
FORCEPROP 1 LAST BODY_TYPE PLUMBING
J 2
(-200 1800);
DISPLAY 0.872340 (-200 1800);
PAINT GREEN (-200 1800);
DISPLAY INVISIBLE (-200 1800);
FORCEPROP 1 LAST HDL_TAP TRUE
J 2
(-525 1625);
DISPLAY 0.872340 (-525 1625);
DISPLAY INVISIBLE (-525 1625);
FORCEPROP 1 LAST PATH I42
J 2
(-198 1750);
DISPLAY 0.872340 (-198 1750);
PAINT GREEN (-198 1750);
DISPLAY INVISIBLE (-198 1750);
FORCEADD TAP..1
R 2
(-200 1800);
FORCEPROP 3 LASTPIN (-150 1800) SIG_NAME M_G_CPU0_SB_DQ<26>
J 0
(-140 1810);
DISPLAY 0.659574 (-140 1810);
PAINT MONO (-140 1810);
DISPLAY INVISIBLE (-140 1810);
FORCEPROP 1 LASTPIN (-150 1800) BN 26
J 2
(-138 1808);
DISPLAY 0.680851 (-138 1808);
PAINT GREEN (-138 1808);
FORCEPROP 2 LAST CDS_LIB standard
J 0
(-200 1800);
DISPLAY INVISIBLE (-200 1800);
FORCEPROP 1 LAST BODY_TYPE PLUMBING
J 2
(-200 1850);
DISPLAY 0.872340 (-200 1850);
PAINT GREEN (-200 1850);
DISPLAY INVISIBLE (-200 1850);
FORCEPROP 1 LAST HDL_TAP TRUE
J 2
(-525 1675);
DISPLAY 0.872340 (-525 1675);
DISPLAY INVISIBLE (-525 1675);
FORCEPROP 1 LAST PATH I43
J 2
(-198 1800);
DISPLAY 0.872340 (-198 1800);
PAINT GREEN (-198 1800);
DISPLAY INVISIBLE (-198 1800);
FORCEADD TAP..1
R 2
(-200 1850);
FORCEPROP 3 LASTPIN (-150 1850) SIG_NAME M_G_CPU0_SB_DQ<27>
J 0
(-140 1860);
DISPLAY 0.659574 (-140 1860);
PAINT MONO (-140 1860);
DISPLAY INVISIBLE (-140 1860);
FORCEPROP 1 LASTPIN (-150 1850) BN 27
J 2
(-138 1858);
DISPLAY 0.680851 (-138 1858);
PAINT GREEN (-138 1858);
FORCEPROP 2 LAST CDS_LIB standard
J 0
(-200 1850);
DISPLAY INVISIBLE (-200 1850);
FORCEPROP 1 LAST BODY_TYPE PLUMBING
J 2
(-200 1900);
DISPLAY 0.872340 (-200 1900);
PAINT GREEN (-200 1900);
DISPLAY INVISIBLE (-200 1900);
FORCEPROP 1 LAST HDL_TAP TRUE
J 2
(-525 1725);
DISPLAY 0.872340 (-525 1725);
DISPLAY INVISIBLE (-525 1725);
FORCEPROP 1 LAST PATH I44
J 2
(-198 1850);
DISPLAY 0.872340 (-198 1850);
PAINT GREEN (-198 1850);
DISPLAY INVISIBLE (-198 1850);
FORCEADD TAP..1
R 2
(-200 1900);
FORCEPROP 3 LASTPIN (-150 1900) SIG_NAME M_G_CPU0_SB_DQ<28>
J 0
(-140 1910);
DISPLAY 0.659574 (-140 1910);
PAINT MONO (-140 1910);
DISPLAY INVISIBLE (-140 1910);
FORCEPROP 1 LASTPIN (-150 1900) BN 28
J 2
(-138 1908);
DISPLAY 0.680851 (-138 1908);
PAINT GREEN (-138 1908);
FORCEPROP 2 LAST CDS_LIB standard
J 0
(-200 1900);
DISPLAY INVISIBLE (-200 1900);
FORCEPROP 1 LAST BODY_TYPE PLUMBING
J 2
(-200 1950);
DISPLAY 0.872340 (-200 1950);
PAINT GREEN (-200 1950);
DISPLAY INVISIBLE (-200 1950);
FORCEPROP 1 LAST HDL_TAP TRUE
J 2
(-525 1775);
DISPLAY 0.872340 (-525 1775);
DISPLAY INVISIBLE (-525 1775);
FORCEPROP 1 LAST PATH I45
J 2
(-198 1900);
DISPLAY 0.872340 (-198 1900);
PAINT GREEN (-198 1900);
DISPLAY INVISIBLE (-198 1900);
FORCEADD TAP..1
R 2
(-200 1950);
FORCEPROP 3 LASTPIN (-150 1950) SIG_NAME M_G_CPU0_SB_DQ<29>
J 0
(-140 1960);
DISPLAY 0.659574 (-140 1960);
PAINT MONO (-140 1960);
DISPLAY INVISIBLE (-140 1960);
FORCEPROP 1 LASTPIN (-150 1950) BN 29
J 2
(-138 1958);
DISPLAY 0.680851 (-138 1958);
PAINT GREEN (-138 1958);
FORCEPROP 2 LAST CDS_LIB standard
J 0
(-200 1950);
DISPLAY INVISIBLE (-200 1950);
FORCEPROP 1 LAST BODY_TYPE PLUMBING
J 2
(-200 2000);
DISPLAY 0.872340 (-200 2000);
PAINT GREEN (-200 2000);
DISPLAY INVISIBLE (-200 2000);
FORCEPROP 1 LAST HDL_TAP TRUE
J 2
(-525 1825);
DISPLAY 0.872340 (-525 1825);
DISPLAY INVISIBLE (-525 1825);
FORCEPROP 1 LAST PATH I46
J 2
(-198 1950);
DISPLAY 0.872340 (-198 1950);
PAINT GREEN (-198 1950);
DISPLAY INVISIBLE (-198 1950);
FORCEADD TAP..1
R 2
(-200 2050);
FORCEPROP 3 LASTPIN (-150 2050) SIG_NAME M_G_CPU0_SB_DQ<31>
J 0
(-140 2060);
DISPLAY 0.659574 (-140 2060);
PAINT MONO (-140 2060);
DISPLAY INVISIBLE (-140 2060);
FORCEPROP 1 LASTPIN (-150 2050) BN 31
J 2
(-138 2058);
DISPLAY 0.680851 (-138 2058);
PAINT GREEN (-138 2058);
FORCEPROP 2 LAST CDS_LIB standard
J 0
(-200 2050);
DISPLAY INVISIBLE (-200 2050);
FORCEPROP 1 LAST BODY_TYPE PLUMBING
J 2
(-200 2100);
DISPLAY 0.872340 (-200 2100);
PAINT GREEN (-200 2100);
DISPLAY INVISIBLE (-200 2100);
FORCEPROP 1 LAST HDL_TAP TRUE
J 2
(-525 1925);
DISPLAY 0.872340 (-525 1925);
DISPLAY INVISIBLE (-525 1925);
FORCEPROP 1 LAST PATH I47
J 2
(-198 2050);
DISPLAY 0.872340 (-198 2050);
PAINT GREEN (-198 2050);
DISPLAY INVISIBLE (-198 2050);
FORCEADD TAP..1
R 2
(-200 2000);
FORCEPROP 3 LASTPIN (-150 2000) SIG_NAME M_G_CPU0_SB_DQ<30>
J 0
(-140 2010);
DISPLAY 0.659574 (-140 2010);
PAINT MONO (-140 2010);
DISPLAY INVISIBLE (-140 2010);
FORCEPROP 1 LASTPIN (-150 2000) BN 30
J 2
(-138 2008);
DISPLAY 0.680851 (-138 2008);
PAINT GREEN (-138 2008);
FORCEPROP 2 LAST CDS_LIB standard
J 0
(-200 2000);
DISPLAY INVISIBLE (-200 2000);
FORCEPROP 1 LAST BODY_TYPE PLUMBING
J 2
(-200 2050);
DISPLAY 0.872340 (-200 2050);
PAINT GREEN (-200 2050);
DISPLAY INVISIBLE (-200 2050);
FORCEPROP 1 LAST HDL_TAP TRUE
J 2
(-525 1875);
DISPLAY 0.872340 (-525 1875);
DISPLAY INVISIBLE (-525 1875);
FORCEPROP 1 LAST PATH I48
J 2
(-198 2000);
DISPLAY 0.872340 (-198 2000);
PAINT GREEN (-198 2000);
DISPLAY INVISIBLE (-198 2000);
FORCEADD TAP..1
R 2
(-200 2200);
FORCEPROP 3 LASTPIN (-150 2200) SIG_NAME M_G_CPU0_SA_CB<2>
J 0
(-140 2210);
DISPLAY 0.659574 (-140 2210);
PAINT MONO (-140 2210);
DISPLAY INVISIBLE (-140 2210);
FORCEPROP 1 LASTPIN (-150 2200) BN 2
J 2
(-138 2208);
DISPLAY 0.680851 (-138 2208);
PAINT GREEN (-138 2208);
FORCEPROP 2 LAST CDS_LIB standard
J 0
(-200 2200);
DISPLAY INVISIBLE (-200 2200);
FORCEPROP 1 LAST BODY_TYPE PLUMBING
J 2
(-200 2250);
DISPLAY 0.872340 (-200 2250);
PAINT GREEN (-200 2250);
DISPLAY INVISIBLE (-200 2250);
FORCEPROP 1 LAST HDL_TAP TRUE
J 2
(-525 2075);
DISPLAY 0.872340 (-525 2075);
DISPLAY INVISIBLE (-525 2075);
FORCEPROP 1 LAST PATH I49
J 2
(-198 2200);
DISPLAY 0.872340 (-198 2200);
PAINT GREEN (-198 2200);
DISPLAY INVISIBLE (-198 2200);
FORCEADD TAP..1
R 2
(-200 150);
FORCEPROP 3 LASTPIN (-150 150) SIG_NAME M_G_CPU0_SB_CB<1>
J 0
(-140 160);
DISPLAY 0.659574 (-140 160);
PAINT MONO (-140 160);
DISPLAY INVISIBLE (-140 160);
FORCEPROP 1 LASTPIN (-150 150) BN 1
J 2
(-138 158);
DISPLAY 0.680851 (-138 158);
PAINT GREEN (-138 158);
FORCEPROP 2 LAST CDS_LIB standard
J 0
(-200 150);
DISPLAY INVISIBLE (-200 150);
FORCEPROP 1 LAST BODY_TYPE PLUMBING
J 2
(-200 200);
DISPLAY 0.872340 (-200 200);
PAINT GREEN (-200 200);
DISPLAY INVISIBLE (-200 200);
FORCEPROP 1 LAST HDL_TAP TRUE
J 2
(-525 25);
DISPLAY 0.872340 (-525 25);
DISPLAY INVISIBLE (-525 25);
FORCEPROP 1 LAST PATH I5
J 2
(-198 150);
DISPLAY 0.872340 (-198 150);
PAINT GREEN (-198 150);
DISPLAY INVISIBLE (-198 150);
FORCEADD TAP..1
R 2
(-200 2150);
FORCEPROP 3 LASTPIN (-150 2150) SIG_NAME M_G_CPU0_SA_CB<1>
J 0
(-140 2160);
DISPLAY 0.659574 (-140 2160);
PAINT MONO (-140 2160);
DISPLAY INVISIBLE (-140 2160);
FORCEPROP 1 LASTPIN (-150 2150) BN 1
J 2
(-138 2158);
DISPLAY 0.680851 (-138 2158);
PAINT GREEN (-138 2158);
FORCEPROP 2 LAST CDS_LIB standard
J 0
(-200 2150);
DISPLAY INVISIBLE (-200 2150);
FORCEPROP 1 LAST BODY_TYPE PLUMBING
J 2
(-200 2200);
DISPLAY 0.872340 (-200 2200);
PAINT GREEN (-200 2200);
DISPLAY INVISIBLE (-200 2200);
FORCEPROP 1 LAST HDL_TAP TRUE
J 2
(-525 2025);
DISPLAY 0.872340 (-525 2025);
DISPLAY INVISIBLE (-525 2025);
FORCEPROP 1 LAST PATH I50
J 2
(-198 2150);
DISPLAY 0.872340 (-198 2150);
PAINT GREEN (-198 2150);
DISPLAY INVISIBLE (-198 2150);
FORCEADD TAP..1
R 2
(-200 2100);
FORCEPROP 3 LASTPIN (-150 2100) SIG_NAME M_G_CPU0_SA_CB<0>
J 0
(-140 2110);
DISPLAY 0.659574 (-140 2110);
PAINT MONO (-140 2110);
DISPLAY INVISIBLE (-140 2110);
FORCEPROP 1 LASTPIN (-150 2100) BN 0
J 2
(-138 2108);
DISPLAY 0.680851 (-138 2108);
PAINT GREEN (-138 2108);
FORCEPROP 2 LAST CDS_LIB standard
J 0
(-200 2100);
DISPLAY INVISIBLE (-200 2100);
FORCEPROP 1 LAST BODY_TYPE PLUMBING
J 2
(-200 2150);
DISPLAY 0.872340 (-200 2150);
PAINT GREEN (-200 2150);
DISPLAY INVISIBLE (-200 2150);
FORCEPROP 1 LAST HDL_TAP TRUE
J 2
(-525 1975);
DISPLAY 0.872340 (-525 1975);
DISPLAY INVISIBLE (-525 1975);
FORCEPROP 1 LAST PATH I51
J 2
(-198 2100);
DISPLAY 0.872340 (-198 2100);
PAINT GREEN (-198 2100);
DISPLAY INVISIBLE (-198 2100);
FORCEADD OFFPAGE..3
R 2
(-1225 2475);
FORCEPROP 2 LAST $XR1 95 
J 0
(-1594 2475);
DISPLAY 0.638298 (-1594 2475);
PAINT MONO (-1594 2475);
FORCEPROP 2 LAST $XR0 94 
J 0
(-1504 2475);
DISPLAY 0.638298 (-1504 2475);
PAINT MONO (-1504 2475);
FORCEPROP 2 LAST CDS_LIB standard
J 0
(-1225 2475);
DISPLAY INVISIBLE (-1225 2475);
FORCEPROP 1 LAST OFFPAGE TRUE
J 2
(-1550 2350);
DISPLAY 0.872340 (-1550 2350);
DISPLAY INVISIBLE (-1550 2350);
FORCEPROP 1 LAST COMMENT_BODY TRUE
J 2
(-1175 2375);
DISPLAY 0.872340 (-1175 2375);
PAINT GREEN (-1175 2375);
DISPLAY INVISIBLE (-1175 2375);
FORCEPROP 2 LAST PATH I52
J 0
(-1175 2550);
DISPLAY 1.021277 (-1175 2550);
DISPLAY INVISIBLE (-1175 2550);
FORCEADD OFFPAGE..3
R 2
(-1225 4075);
FORCEPROP 2 LAST $XR1 95 
J 0
(-1594 4075);
DISPLAY 0.638298 (-1594 4075);
PAINT MONO (-1594 4075);
FORCEPROP 2 LAST $XR0 94 
J 0
(-1504 4075);
DISPLAY 0.638298 (-1504 4075);
PAINT MONO (-1504 4075);
FORCEPROP 2 LAST CDS_LIB standard
J 0
(-1225 4075);
DISPLAY INVISIBLE (-1225 4075);
FORCEPROP 1 LAST OFFPAGE TRUE
J 2
(-1550 3950);
DISPLAY 0.872340 (-1550 3950);
DISPLAY INVISIBLE (-1550 3950);
FORCEPROP 1 LAST COMMENT_BODY TRUE
J 2
(-1175 3975);
DISPLAY 0.872340 (-1175 3975);
PAINT GREEN (-1175 3975);
DISPLAY INVISIBLE (-1175 3975);
FORCEPROP 2 LAST PATH I53
J 0
(-1175 4150);
DISPLAY 1.021277 (-1175 4150);
DISPLAY INVISIBLE (-1175 4150);
FORCEADD TAP..1
R 2
(-200 2300);
FORCEPROP 3 LASTPIN (-150 2300) SIG_NAME M_G_CPU0_SA_CB<4>
J 0
(-140 2310);
DISPLAY 0.659574 (-140 2310);
PAINT MONO (-140 2310);
DISPLAY INVISIBLE (-140 2310);
FORCEPROP 1 LASTPIN (-150 2300) BN 4
J 2
(-138 2308);
DISPLAY 0.680851 (-138 2308);
PAINT GREEN (-138 2308);
FORCEPROP 2 LAST CDS_LIB standard
J 0
(-200 2300);
DISPLAY INVISIBLE (-200 2300);
FORCEPROP 1 LAST BODY_TYPE PLUMBING
J 2
(-200 2350);
DISPLAY 0.872340 (-200 2350);
PAINT GREEN (-200 2350);
DISPLAY INVISIBLE (-200 2350);
FORCEPROP 1 LAST HDL_TAP TRUE
J 2
(-525 2175);
DISPLAY 0.872340 (-525 2175);
DISPLAY INVISIBLE (-525 2175);
FORCEPROP 1 LAST PATH I54
J 2
(-198 2300);
DISPLAY 0.872340 (-198 2300);
PAINT GREEN (-198 2300);
DISPLAY INVISIBLE (-198 2300);
FORCEADD TAP..1
R 2
(-200 2350);
FORCEPROP 3 LASTPIN (-150 2350) SIG_NAME M_G_CPU0_SA_CB<5>
J 0
(-140 2360);
DISPLAY 0.659574 (-140 2360);
PAINT MONO (-140 2360);
DISPLAY INVISIBLE (-140 2360);
FORCEPROP 1 LASTPIN (-150 2350) BN 5
J 2
(-138 2358);
DISPLAY 0.680851 (-138 2358);
PAINT GREEN (-138 2358);
FORCEPROP 2 LAST CDS_LIB standard
J 0
(-200 2350);
DISPLAY INVISIBLE (-200 2350);
FORCEPROP 1 LAST BODY_TYPE PLUMBING
J 2
(-200 2400);
DISPLAY 0.872340 (-200 2400);
PAINT GREEN (-200 2400);
DISPLAY INVISIBLE (-200 2400);
FORCEPROP 1 LAST HDL_TAP TRUE
J 2
(-525 2225);
DISPLAY 0.872340 (-525 2225);
DISPLAY INVISIBLE (-525 2225);
FORCEPROP 1 LAST PATH I55
J 2
(-198 2350);
DISPLAY 0.872340 (-198 2350);
PAINT GREEN (-198 2350);
DISPLAY INVISIBLE (-198 2350);
FORCEADD TAP..1
R 2
(-200 2250);
FORCEPROP 3 LASTPIN (-150 2250) SIG_NAME M_G_CPU0_SA_CB<3>
J 0
(-140 2260);
DISPLAY 0.659574 (-140 2260);
PAINT MONO (-140 2260);
DISPLAY INVISIBLE (-140 2260);
FORCEPROP 1 LASTPIN (-150 2250) BN 3
J 2
(-138 2258);
DISPLAY 0.680851 (-138 2258);
PAINT GREEN (-138 2258);
FORCEPROP 2 LAST CDS_LIB standard
J 0
(-200 2250);
DISPLAY INVISIBLE (-200 2250);
FORCEPROP 1 LAST BODY_TYPE PLUMBING
J 2
(-200 2300);
DISPLAY 0.872340 (-200 2300);
PAINT GREEN (-200 2300);
DISPLAY INVISIBLE (-200 2300);
FORCEPROP 1 LAST HDL_TAP TRUE
J 2
(-525 2125);
DISPLAY 0.872340 (-525 2125);
DISPLAY INVISIBLE (-525 2125);
FORCEPROP 1 LAST PATH I56
J 2
(-198 2250);
DISPLAY 0.872340 (-198 2250);
PAINT GREEN (-198 2250);
DISPLAY INVISIBLE (-198 2250);
FORCEADD TAP..1
R 2
(-200 2450);
FORCEPROP 3 LASTPIN (-150 2450) SIG_NAME M_G_CPU0_SA_CB<7>
J 0
(-140 2460);
DISPLAY 0.659574 (-140 2460);
PAINT MONO (-140 2460);
DISPLAY INVISIBLE (-140 2460);
FORCEPROP 1 LASTPIN (-150 2450) BN 7
J 2
(-138 2458);
DISPLAY 0.680851 (-138 2458);
PAINT GREEN (-138 2458);
FORCEPROP 2 LAST CDS_LIB standard
J 0
(-200 2450);
DISPLAY INVISIBLE (-200 2450);
FORCEPROP 1 LAST BODY_TYPE PLUMBING
J 2
(-200 2500);
DISPLAY 0.872340 (-200 2500);
PAINT GREEN (-200 2500);
DISPLAY INVISIBLE (-200 2500);
FORCEPROP 1 LAST HDL_TAP TRUE
J 2
(-525 2325);
DISPLAY 0.872340 (-525 2325);
DISPLAY INVISIBLE (-525 2325);
FORCEPROP 1 LAST PATH I57
J 2
(-198 2450);
DISPLAY 0.872340 (-198 2450);
PAINT GREEN (-198 2450);
DISPLAY INVISIBLE (-198 2450);
FORCEADD TAP..1
R 2
(-200 2400);
FORCEPROP 3 LASTPIN (-150 2400) SIG_NAME M_G_CPU0_SA_CB<6>
J 0
(-140 2410);
DISPLAY 0.659574 (-140 2410);
PAINT MONO (-140 2410);
DISPLAY INVISIBLE (-140 2410);
FORCEPROP 1 LASTPIN (-150 2400) BN 6
J 2
(-138 2408);
DISPLAY 0.680851 (-138 2408);
PAINT GREEN (-138 2408);
FORCEPROP 2 LAST CDS_LIB standard
J 0
(-200 2400);
DISPLAY INVISIBLE (-200 2400);
FORCEPROP 1 LAST BODY_TYPE PLUMBING
J 2
(-200 2450);
DISPLAY 0.872340 (-200 2450);
PAINT GREEN (-200 2450);
DISPLAY INVISIBLE (-200 2450);
FORCEPROP 1 LAST HDL_TAP TRUE
J 2
(-525 2275);
DISPLAY 0.872340 (-525 2275);
DISPLAY INVISIBLE (-525 2275);
FORCEPROP 1 LAST PATH I58
J 2
(-198 2400);
DISPLAY 0.872340 (-198 2400);
PAINT GREEN (-198 2400);
DISPLAY INVISIBLE (-198 2400);
FORCEADD TAP..1
R 2
(-200 2550);
FORCEPROP 3 LASTPIN (-150 2550) SIG_NAME M_G_CPU0_SA_DQ<1>
J 0
(-140 2560);
DISPLAY 0.659574 (-140 2560);
PAINT MONO (-140 2560);
DISPLAY INVISIBLE (-140 2560);
FORCEPROP 1 LASTPIN (-150 2550) BN 1
J 2
(-138 2558);
DISPLAY 0.680851 (-138 2558);
PAINT GREEN (-138 2558);
FORCEPROP 2 LAST CDS_LIB standard
J 0
(-200 2550);
DISPLAY INVISIBLE (-200 2550);
FORCEPROP 1 LAST BODY_TYPE PLUMBING
J 2
(-200 2600);
DISPLAY 0.872340 (-200 2600);
PAINT GREEN (-200 2600);
DISPLAY INVISIBLE (-200 2600);
FORCEPROP 1 LAST HDL_TAP TRUE
J 2
(-525 2425);
DISPLAY 0.872340 (-525 2425);
DISPLAY INVISIBLE (-525 2425);
FORCEPROP 1 LAST PATH I59
J 2
(-198 2550);
DISPLAY 0.872340 (-198 2550);
PAINT GREEN (-198 2550);
DISPLAY INVISIBLE (-198 2550);
FORCEADD TAP..1
R 2
(-200 100);
FORCEPROP 3 LASTPIN (-150 100) SIG_NAME M_G_CPU0_SB_CB<0>
J 0
(-140 110);
DISPLAY 0.659574 (-140 110);
PAINT MONO (-140 110);
DISPLAY INVISIBLE (-140 110);
FORCEPROP 1 LASTPIN (-150 100) BN 0
J 2
(-138 108);
DISPLAY 0.680851 (-138 108);
PAINT GREEN (-138 108);
FORCEPROP 2 LAST CDS_LIB standard
J 0
(-200 100);
DISPLAY INVISIBLE (-200 100);
FORCEPROP 1 LAST BODY_TYPE PLUMBING
J 2
(-200 150);
DISPLAY 0.872340 (-200 150);
PAINT GREEN (-200 150);
DISPLAY INVISIBLE (-200 150);
FORCEPROP 1 LAST HDL_TAP TRUE
J 2
(-525 -25);
DISPLAY 0.872340 (-525 -25);
DISPLAY INVISIBLE (-525 -25);
FORCEPROP 1 LAST PATH I6
J 2
(-198 100);
DISPLAY 0.872340 (-198 100);
PAINT GREEN (-198 100);
DISPLAY INVISIBLE (-198 100);
FORCEADD TAP..1
R 2
(-200 2500);
FORCEPROP 3 LASTPIN (-150 2500) SIG_NAME M_G_CPU0_SA_DQ<0>
J 0
(-140 2510);
DISPLAY 0.659574 (-140 2510);
PAINT MONO (-140 2510);
DISPLAY INVISIBLE (-140 2510);
FORCEPROP 1 LASTPIN (-150 2500) BN 0
J 2
(-138 2508);
DISPLAY 0.680851 (-138 2508);
PAINT GREEN (-138 2508);
FORCEPROP 2 LAST CDS_LIB standard
J 0
(-200 2500);
DISPLAY INVISIBLE (-200 2500);
FORCEPROP 1 LAST BODY_TYPE PLUMBING
J 2
(-200 2550);
DISPLAY 0.872340 (-200 2550);
PAINT GREEN (-200 2550);
DISPLAY INVISIBLE (-200 2550);
FORCEPROP 1 LAST HDL_TAP TRUE
J 2
(-525 2375);
DISPLAY 0.872340 (-525 2375);
DISPLAY INVISIBLE (-525 2375);
FORCEPROP 1 LAST PATH I60
J 2
(-198 2500);
DISPLAY 0.872340 (-198 2500);
PAINT GREEN (-198 2500);
DISPLAY INVISIBLE (-198 2500);
FORCEADD TAP..1
R 2
(-200 2600);
FORCEPROP 3 LASTPIN (-150 2600) SIG_NAME M_G_CPU0_SA_DQ<2>
J 0
(-140 2610);
DISPLAY 0.659574 (-140 2610);
PAINT MONO (-140 2610);
DISPLAY INVISIBLE (-140 2610);
FORCEPROP 1 LASTPIN (-150 2600) BN 2
J 2
(-138 2608);
DISPLAY 0.680851 (-138 2608);
PAINT GREEN (-138 2608);
FORCEPROP 2 LAST CDS_LIB standard
J 0
(-200 2600);
DISPLAY INVISIBLE (-200 2600);
FORCEPROP 1 LAST BODY_TYPE PLUMBING
J 2
(-200 2650);
DISPLAY 0.872340 (-200 2650);
PAINT GREEN (-200 2650);
DISPLAY INVISIBLE (-200 2650);
FORCEPROP 1 LAST HDL_TAP TRUE
J 2
(-525 2475);
DISPLAY 0.872340 (-525 2475);
DISPLAY INVISIBLE (-525 2475);
FORCEPROP 1 LAST PATH I61
J 2
(-198 2600);
DISPLAY 0.872340 (-198 2600);
PAINT GREEN (-198 2600);
DISPLAY INVISIBLE (-198 2600);
FORCEADD TAP..1
R 2
(-200 2700);
FORCEPROP 3 LASTPIN (-150 2700) SIG_NAME M_G_CPU0_SA_DQ<4>
J 0
(-140 2710);
DISPLAY 0.659574 (-140 2710);
PAINT MONO (-140 2710);
DISPLAY INVISIBLE (-140 2710);
FORCEPROP 1 LASTPIN (-150 2700) BN 4
J 2
(-138 2708);
DISPLAY 0.680851 (-138 2708);
PAINT GREEN (-138 2708);
FORCEPROP 2 LAST CDS_LIB standard
J 0
(-200 2700);
DISPLAY INVISIBLE (-200 2700);
FORCEPROP 1 LAST BODY_TYPE PLUMBING
J 2
(-200 2750);
DISPLAY 0.872340 (-200 2750);
PAINT GREEN (-200 2750);
DISPLAY INVISIBLE (-200 2750);
FORCEPROP 1 LAST HDL_TAP TRUE
J 2
(-525 2575);
DISPLAY 0.872340 (-525 2575);
DISPLAY INVISIBLE (-525 2575);
FORCEPROP 1 LAST PATH I62
J 2
(-198 2700);
DISPLAY 0.872340 (-198 2700);
PAINT GREEN (-198 2700);
DISPLAY INVISIBLE (-198 2700);
FORCEADD TAP..1
R 2
(-200 2650);
FORCEPROP 3 LASTPIN (-150 2650) SIG_NAME M_G_CPU0_SA_DQ<3>
J 0
(-140 2660);
DISPLAY 0.659574 (-140 2660);
PAINT MONO (-140 2660);
DISPLAY INVISIBLE (-140 2660);
FORCEPROP 1 LASTPIN (-150 2650) BN 3
J 2
(-138 2658);
DISPLAY 0.680851 (-138 2658);
PAINT GREEN (-138 2658);
FORCEPROP 2 LAST CDS_LIB standard
J 0
(-200 2650);
DISPLAY INVISIBLE (-200 2650);
FORCEPROP 1 LAST BODY_TYPE PLUMBING
J 2
(-200 2700);
DISPLAY 0.872340 (-200 2700);
PAINT GREEN (-200 2700);
DISPLAY INVISIBLE (-200 2700);
FORCEPROP 1 LAST HDL_TAP TRUE
J 2
(-525 2525);
DISPLAY 0.872340 (-525 2525);
DISPLAY INVISIBLE (-525 2525);
FORCEPROP 1 LAST PATH I63
J 2
(-198 2650);
DISPLAY 0.872340 (-198 2650);
PAINT GREEN (-198 2650);
DISPLAY INVISIBLE (-198 2650);
FORCEADD TAP..1
R 2
(-200 2750);
FORCEPROP 3 LASTPIN (-150 2750) SIG_NAME M_G_CPU0_SA_DQ<5>
J 0
(-140 2760);
DISPLAY 0.659574 (-140 2760);
PAINT MONO (-140 2760);
DISPLAY INVISIBLE (-140 2760);
FORCEPROP 1 LASTPIN (-150 2750) BN 5
J 2
(-138 2758);
DISPLAY 0.680851 (-138 2758);
PAINT GREEN (-138 2758);
FORCEPROP 2 LAST CDS_LIB standard
J 0
(-200 2750);
DISPLAY INVISIBLE (-200 2750);
FORCEPROP 1 LAST BODY_TYPE PLUMBING
J 2
(-200 2800);
DISPLAY 0.872340 (-200 2800);
PAINT GREEN (-200 2800);
DISPLAY INVISIBLE (-200 2800);
FORCEPROP 1 LAST HDL_TAP TRUE
J 2
(-525 2625);
DISPLAY 0.872340 (-525 2625);
DISPLAY INVISIBLE (-525 2625);
FORCEPROP 1 LAST PATH I64
J 2
(-198 2750);
DISPLAY 0.872340 (-198 2750);
PAINT GREEN (-198 2750);
DISPLAY INVISIBLE (-198 2750);
FORCEADD TAP..1
R 2
(-200 2850);
FORCEPROP 3 LASTPIN (-150 2850) SIG_NAME M_G_CPU0_SA_DQ<7>
J 0
(-140 2860);
DISPLAY 0.659574 (-140 2860);
PAINT MONO (-140 2860);
DISPLAY INVISIBLE (-140 2860);
FORCEPROP 1 LASTPIN (-150 2850) BN 7
J 2
(-138 2858);
DISPLAY 0.680851 (-138 2858);
PAINT GREEN (-138 2858);
FORCEPROP 2 LAST CDS_LIB standard
J 0
(-200 2850);
DISPLAY INVISIBLE (-200 2850);
FORCEPROP 1 LAST BODY_TYPE PLUMBING
J 2
(-200 2900);
DISPLAY 0.872340 (-200 2900);
PAINT GREEN (-200 2900);
DISPLAY INVISIBLE (-200 2900);
FORCEPROP 1 LAST HDL_TAP TRUE
J 2
(-525 2725);
DISPLAY 0.872340 (-525 2725);
DISPLAY INVISIBLE (-525 2725);
FORCEPROP 1 LAST PATH I65
J 2
(-198 2850);
DISPLAY 0.872340 (-198 2850);
PAINT GREEN (-198 2850);
DISPLAY INVISIBLE (-198 2850);
FORCEADD TAP..1
R 2
(-200 2800);
FORCEPROP 3 LASTPIN (-150 2800) SIG_NAME M_G_CPU0_SA_DQ<6>
J 0
(-140 2810);
DISPLAY 0.659574 (-140 2810);
PAINT MONO (-140 2810);
DISPLAY INVISIBLE (-140 2810);
FORCEPROP 1 LASTPIN (-150 2800) BN 6
J 2
(-138 2808);
DISPLAY 0.680851 (-138 2808);
PAINT GREEN (-138 2808);
FORCEPROP 2 LAST CDS_LIB standard
J 0
(-200 2800);
DISPLAY INVISIBLE (-200 2800);
FORCEPROP 1 LAST BODY_TYPE PLUMBING
J 2
(-200 2850);
DISPLAY 0.872340 (-200 2850);
PAINT GREEN (-200 2850);
DISPLAY INVISIBLE (-200 2850);
FORCEPROP 1 LAST HDL_TAP TRUE
J 2
(-525 2675);
DISPLAY 0.872340 (-525 2675);
DISPLAY INVISIBLE (-525 2675);
FORCEPROP 1 LAST PATH I66
J 2
(-198 2800);
DISPLAY 0.872340 (-198 2800);
PAINT GREEN (-198 2800);
DISPLAY INVISIBLE (-198 2800);
FORCEADD TAP..1
R 2
(-200 2950);
FORCEPROP 3 LASTPIN (-150 2950) SIG_NAME M_G_CPU0_SA_DQ<9>
J 0
(-140 2960);
DISPLAY 0.659574 (-140 2960);
PAINT MONO (-140 2960);
DISPLAY INVISIBLE (-140 2960);
FORCEPROP 1 LASTPIN (-150 2950) BN 9
J 2
(-138 2958);
DISPLAY 0.680851 (-138 2958);
PAINT GREEN (-138 2958);
FORCEPROP 2 LAST CDS_LIB standard
J 0
(-200 2950);
DISPLAY INVISIBLE (-200 2950);
FORCEPROP 1 LAST BODY_TYPE PLUMBING
J 2
(-200 3000);
DISPLAY 0.872340 (-200 3000);
PAINT GREEN (-200 3000);
DISPLAY INVISIBLE (-200 3000);
FORCEPROP 1 LAST HDL_TAP TRUE
J 2
(-525 2825);
DISPLAY 0.872340 (-525 2825);
DISPLAY INVISIBLE (-525 2825);
FORCEPROP 1 LAST PATH I67
J 2
(-198 2950);
DISPLAY 0.872340 (-198 2950);
PAINT GREEN (-198 2950);
DISPLAY INVISIBLE (-198 2950);
FORCEADD TAP..1
R 2
(-200 2900);
FORCEPROP 3 LASTPIN (-150 2900) SIG_NAME M_G_CPU0_SA_DQ<8>
J 0
(-140 2910);
DISPLAY 0.659574 (-140 2910);
PAINT MONO (-140 2910);
DISPLAY INVISIBLE (-140 2910);
FORCEPROP 1 LASTPIN (-150 2900) BN 8
J 2
(-138 2908);
DISPLAY 0.680851 (-138 2908);
PAINT GREEN (-138 2908);
FORCEPROP 2 LAST CDS_LIB standard
J 0
(-200 2900);
DISPLAY INVISIBLE (-200 2900);
FORCEPROP 1 LAST BODY_TYPE PLUMBING
J 2
(-200 2950);
DISPLAY 0.872340 (-200 2950);
PAINT GREEN (-200 2950);
DISPLAY INVISIBLE (-200 2950);
FORCEPROP 1 LAST HDL_TAP TRUE
J 2
(-525 2775);
DISPLAY 0.872340 (-525 2775);
DISPLAY INVISIBLE (-525 2775);
FORCEPROP 1 LAST PATH I68
J 2
(-198 2900);
DISPLAY 0.872340 (-198 2900);
PAINT GREEN (-198 2900);
DISPLAY INVISIBLE (-198 2900);
FORCEADD TAP..1
R 2
(-200 3000);
FORCEPROP 3 LASTPIN (-150 3000) SIG_NAME M_G_CPU0_SA_DQ<10>
J 0
(-140 3010);
DISPLAY 0.659574 (-140 3010);
PAINT MONO (-140 3010);
DISPLAY INVISIBLE (-140 3010);
FORCEPROP 1 LASTPIN (-150 3000) BN 10
J 2
(-138 3008);
DISPLAY 0.680851 (-138 3008);
PAINT GREEN (-138 3008);
FORCEPROP 2 LAST CDS_LIB standard
J 0
(-200 3000);
DISPLAY INVISIBLE (-200 3000);
FORCEPROP 1 LAST BODY_TYPE PLUMBING
J 2
(-200 3050);
DISPLAY 0.872340 (-200 3050);
PAINT GREEN (-200 3050);
DISPLAY INVISIBLE (-200 3050);
FORCEPROP 1 LAST HDL_TAP TRUE
J 2
(-525 2875);
DISPLAY 0.872340 (-525 2875);
DISPLAY INVISIBLE (-525 2875);
FORCEPROP 1 LAST PATH I69
J 2
(-198 3000);
DISPLAY 0.872340 (-198 3000);
PAINT GREEN (-198 3000);
DISPLAY INVISIBLE (-198 3000);
FORCEADD TAP..1
R 2
(-200 -50);
FORCEPROP 3 LASTPIN (-150 -50) SIG_NAME M_G_CPU0_CLK_DP<0>
J 0
(-140 -40);
DISPLAY 0.659574 (-140 -40);
PAINT MONO (-140 -40);
DISPLAY INVISIBLE (-140 -40);
FORCEPROP 1 LASTPIN (-150 -50) BN 0
J 2
(-138 -42);
DISPLAY 0.680851 (-138 -42);
PAINT GREEN (-138 -42);
FORCEPROP 2 LAST CDS_LIB standard
J 0
(-200 -50);
DISPLAY INVISIBLE (-200 -50);
FORCEPROP 1 LAST BODY_TYPE PLUMBING
J 2
(-200 0);
DISPLAY 0.872340 (-200 0);
PAINT GREEN (-200 0);
DISPLAY INVISIBLE (-200 0);
FORCEPROP 1 LAST HDL_TAP TRUE
J 2
(-525 -175);
DISPLAY 0.872340 (-525 -175);
DISPLAY INVISIBLE (-525 -175);
FORCEPROP 1 LAST PATH I7
J 2
(-198 -50);
DISPLAY 0.872340 (-198 -50);
PAINT GREEN (-198 -50);
DISPLAY INVISIBLE (-198 -50);
FORCEADD TAP..1
R 2
(-200 3050);
FORCEPROP 3 LASTPIN (-150 3050) SIG_NAME M_G_CPU0_SA_DQ<11>
J 0
(-140 3060);
DISPLAY 0.659574 (-140 3060);
PAINT MONO (-140 3060);
DISPLAY INVISIBLE (-140 3060);
FORCEPROP 1 LASTPIN (-150 3050) BN 11
J 2
(-138 3058);
DISPLAY 0.680851 (-138 3058);
PAINT GREEN (-138 3058);
FORCEPROP 2 LAST CDS_LIB standard
J 0
(-200 3050);
DISPLAY INVISIBLE (-200 3050);
FORCEPROP 1 LAST BODY_TYPE PLUMBING
J 2
(-200 3100);
DISPLAY 0.872340 (-200 3100);
PAINT GREEN (-200 3100);
DISPLAY INVISIBLE (-200 3100);
FORCEPROP 1 LAST HDL_TAP TRUE
J 2
(-525 2925);
DISPLAY 0.872340 (-525 2925);
DISPLAY INVISIBLE (-525 2925);
FORCEPROP 1 LAST PATH I70
J 2
(-198 3050);
DISPLAY 0.872340 (-198 3050);
PAINT GREEN (-198 3050);
DISPLAY INVISIBLE (-198 3050);
FORCEADD TAP..1
R 2
(-200 3100);
FORCEPROP 3 LASTPIN (-150 3100) SIG_NAME M_G_CPU0_SA_DQ<12>
J 0
(-140 3110);
DISPLAY 0.659574 (-140 3110);
PAINT MONO (-140 3110);
DISPLAY INVISIBLE (-140 3110);
FORCEPROP 1 LASTPIN (-150 3100) BN 12
J 2
(-138 3108);
DISPLAY 0.680851 (-138 3108);
PAINT GREEN (-138 3108);
FORCEPROP 2 LAST CDS_LIB standard
J 0
(-200 3100);
DISPLAY INVISIBLE (-200 3100);
FORCEPROP 1 LAST BODY_TYPE PLUMBING
J 2
(-200 3150);
DISPLAY 0.872340 (-200 3150);
PAINT GREEN (-200 3150);
DISPLAY INVISIBLE (-200 3150);
FORCEPROP 1 LAST HDL_TAP TRUE
J 2
(-525 2975);
DISPLAY 0.872340 (-525 2975);
DISPLAY INVISIBLE (-525 2975);
FORCEPROP 1 LAST PATH I71
J 2
(-198 3100);
DISPLAY 0.872340 (-198 3100);
PAINT GREEN (-198 3100);
DISPLAY INVISIBLE (-198 3100);
FORCEADD TAP..1
R 2
(-200 3200);
FORCEPROP 3 LASTPIN (-150 3200) SIG_NAME M_G_CPU0_SA_DQ<14>
J 0
(-140 3210);
DISPLAY 0.659574 (-140 3210);
PAINT MONO (-140 3210);
DISPLAY INVISIBLE (-140 3210);
FORCEPROP 1 LASTPIN (-150 3200) BN 14
J 2
(-138 3208);
DISPLAY 0.680851 (-138 3208);
PAINT GREEN (-138 3208);
FORCEPROP 2 LAST CDS_LIB standard
J 0
(-200 3200);
DISPLAY INVISIBLE (-200 3200);
FORCEPROP 1 LAST BODY_TYPE PLUMBING
J 2
(-200 3250);
DISPLAY 0.872340 (-200 3250);
PAINT GREEN (-200 3250);
DISPLAY INVISIBLE (-200 3250);
FORCEPROP 1 LAST HDL_TAP TRUE
J 2
(-525 3075);
DISPLAY 0.872340 (-525 3075);
DISPLAY INVISIBLE (-525 3075);
FORCEPROP 1 LAST PATH I72
J 2
(-198 3200);
DISPLAY 0.872340 (-198 3200);
PAINT GREEN (-198 3200);
DISPLAY INVISIBLE (-198 3200);
FORCEADD TAP..1
R 2
(-200 3150);
FORCEPROP 3 LASTPIN (-150 3150) SIG_NAME M_G_CPU0_SA_DQ<13>
J 0
(-140 3160);
DISPLAY 0.659574 (-140 3160);
PAINT MONO (-140 3160);
DISPLAY INVISIBLE (-140 3160);
FORCEPROP 1 LASTPIN (-150 3150) BN 13
J 2
(-138 3158);
DISPLAY 0.680851 (-138 3158);
PAINT GREEN (-138 3158);
FORCEPROP 2 LAST CDS_LIB standard
J 0
(-200 3150);
DISPLAY INVISIBLE (-200 3150);
FORCEPROP 1 LAST BODY_TYPE PLUMBING
J 2
(-200 3200);
DISPLAY 0.872340 (-200 3200);
PAINT GREEN (-200 3200);
DISPLAY INVISIBLE (-200 3200);
FORCEPROP 1 LAST HDL_TAP TRUE
J 2
(-525 3025);
DISPLAY 0.872340 (-525 3025);
DISPLAY INVISIBLE (-525 3025);
FORCEPROP 1 LAST PATH I73
J 2
(-198 3150);
DISPLAY 0.872340 (-198 3150);
PAINT GREEN (-198 3150);
DISPLAY INVISIBLE (-198 3150);
FORCEADD TAP..1
R 2
(-200 3250);
FORCEPROP 3 LASTPIN (-150 3250) SIG_NAME M_G_CPU0_SA_DQ<15>
J 0
(-140 3260);
DISPLAY 0.659574 (-140 3260);
PAINT MONO (-140 3260);
DISPLAY INVISIBLE (-140 3260);
FORCEPROP 1 LASTPIN (-150 3250) BN 15
J 2
(-138 3258);
DISPLAY 0.680851 (-138 3258);
PAINT GREEN (-138 3258);
FORCEPROP 2 LAST CDS_LIB standard
J 0
(-200 3250);
DISPLAY INVISIBLE (-200 3250);
FORCEPROP 1 LAST BODY_TYPE PLUMBING
J 2
(-200 3300);
DISPLAY 0.872340 (-200 3300);
PAINT GREEN (-200 3300);
DISPLAY INVISIBLE (-200 3300);
FORCEPROP 1 LAST HDL_TAP TRUE
J 2
(-525 3125);
DISPLAY 0.872340 (-525 3125);
DISPLAY INVISIBLE (-525 3125);
FORCEPROP 1 LAST PATH I74
J 2
(-198 3250);
DISPLAY 0.872340 (-198 3250);
PAINT GREEN (-198 3250);
DISPLAY INVISIBLE (-198 3250);
FORCEADD TAP..1
R 2
(-200 3300);
FORCEPROP 3 LASTPIN (-150 3300) SIG_NAME M_G_CPU0_SA_DQ<16>
J 0
(-140 3310);
DISPLAY 0.659574 (-140 3310);
PAINT MONO (-140 3310);
DISPLAY INVISIBLE (-140 3310);
FORCEPROP 1 LASTPIN (-150 3300) BN 16
J 2
(-138 3308);
DISPLAY 0.680851 (-138 3308);
PAINT GREEN (-138 3308);
FORCEPROP 2 LAST CDS_LIB standard
J 0
(-200 3300);
DISPLAY INVISIBLE (-200 3300);
FORCEPROP 1 LAST BODY_TYPE PLUMBING
J 2
(-200 3350);
DISPLAY 0.872340 (-200 3350);
PAINT GREEN (-200 3350);
DISPLAY INVISIBLE (-200 3350);
FORCEPROP 1 LAST HDL_TAP TRUE
J 2
(-525 3175);
DISPLAY 0.872340 (-525 3175);
DISPLAY INVISIBLE (-525 3175);
FORCEPROP 1 LAST PATH I75
J 2
(-198 3300);
DISPLAY 0.872340 (-198 3300);
PAINT GREEN (-198 3300);
DISPLAY INVISIBLE (-198 3300);
FORCEADD TAP..1
R 2
(-200 3350);
FORCEPROP 3 LASTPIN (-150 3350) SIG_NAME M_G_CPU0_SA_DQ<17>
J 0
(-140 3360);
DISPLAY 0.659574 (-140 3360);
PAINT MONO (-140 3360);
DISPLAY INVISIBLE (-140 3360);
FORCEPROP 1 LASTPIN (-150 3350) BN 17
J 2
(-138 3358);
DISPLAY 0.680851 (-138 3358);
PAINT GREEN (-138 3358);
FORCEPROP 2 LAST CDS_LIB standard
J 0
(-200 3350);
DISPLAY INVISIBLE (-200 3350);
FORCEPROP 1 LAST BODY_TYPE PLUMBING
J 2
(-200 3400);
DISPLAY 0.872340 (-200 3400);
PAINT GREEN (-200 3400);
DISPLAY INVISIBLE (-200 3400);
FORCEPROP 1 LAST HDL_TAP TRUE
J 2
(-525 3225);
DISPLAY 0.872340 (-525 3225);
DISPLAY INVISIBLE (-525 3225);
FORCEPROP 1 LAST PATH I76
J 2
(-198 3350);
DISPLAY 0.872340 (-198 3350);
PAINT GREEN (-198 3350);
DISPLAY INVISIBLE (-198 3350);
FORCEADD TAP..1
R 2
(-200 3450);
FORCEPROP 3 LASTPIN (-150 3450) SIG_NAME M_G_CPU0_SA_DQ<19>
J 0
(-140 3460);
DISPLAY 0.659574 (-140 3460);
PAINT MONO (-140 3460);
DISPLAY INVISIBLE (-140 3460);
FORCEPROP 1 LASTPIN (-150 3450) BN 19
J 2
(-138 3458);
DISPLAY 0.680851 (-138 3458);
PAINT GREEN (-138 3458);
FORCEPROP 2 LAST CDS_LIB standard
J 0
(-200 3450);
DISPLAY INVISIBLE (-200 3450);
FORCEPROP 1 LAST BODY_TYPE PLUMBING
J 2
(-200 3500);
DISPLAY 0.872340 (-200 3500);
PAINT GREEN (-200 3500);
DISPLAY INVISIBLE (-200 3500);
FORCEPROP 1 LAST HDL_TAP TRUE
J 2
(-525 3325);
DISPLAY 0.872340 (-525 3325);
DISPLAY INVISIBLE (-525 3325);
FORCEPROP 1 LAST PATH I77
J 2
(-198 3450);
DISPLAY 0.872340 (-198 3450);
PAINT GREEN (-198 3450);
DISPLAY INVISIBLE (-198 3450);
FORCEADD TAP..1
R 2
(-200 3500);
FORCEPROP 3 LASTPIN (-150 3500) SIG_NAME M_G_CPU0_SA_DQ<20>
J 0
(-140 3510);
DISPLAY 0.659574 (-140 3510);
PAINT MONO (-140 3510);
DISPLAY INVISIBLE (-140 3510);
FORCEPROP 1 LASTPIN (-150 3500) BN 20
J 2
(-138 3508);
DISPLAY 0.680851 (-138 3508);
PAINT GREEN (-138 3508);
FORCEPROP 2 LAST CDS_LIB standard
J 0
(-200 3500);
DISPLAY INVISIBLE (-200 3500);
FORCEPROP 1 LAST BODY_TYPE PLUMBING
J 2
(-200 3550);
DISPLAY 0.872340 (-200 3550);
PAINT GREEN (-200 3550);
DISPLAY INVISIBLE (-200 3550);
FORCEPROP 1 LAST HDL_TAP TRUE
J 2
(-525 3375);
DISPLAY 0.872340 (-525 3375);
DISPLAY INVISIBLE (-525 3375);
FORCEPROP 1 LAST PATH I78
J 2
(-198 3500);
DISPLAY 0.872340 (-198 3500);
PAINT GREEN (-198 3500);
DISPLAY INVISIBLE (-198 3500);
FORCEADD TAP..1
R 2
(-200 3400);
FORCEPROP 3 LASTPIN (-150 3400) SIG_NAME M_G_CPU0_SA_DQ<18>
J 0
(-140 3410);
DISPLAY 0.659574 (-140 3410);
PAINT MONO (-140 3410);
DISPLAY INVISIBLE (-140 3410);
FORCEPROP 1 LASTPIN (-150 3400) BN 18
J 2
(-138 3408);
DISPLAY 0.680851 (-138 3408);
PAINT GREEN (-138 3408);
FORCEPROP 2 LAST CDS_LIB standard
J 0
(-200 3400);
DISPLAY INVISIBLE (-200 3400);
FORCEPROP 1 LAST BODY_TYPE PLUMBING
J 2
(-200 3450);
DISPLAY 0.872340 (-200 3450);
PAINT GREEN (-200 3450);
DISPLAY INVISIBLE (-200 3450);
FORCEPROP 1 LAST HDL_TAP TRUE
J 2
(-525 3275);
DISPLAY 0.872340 (-525 3275);
DISPLAY INVISIBLE (-525 3275);
FORCEPROP 1 LAST PATH I79
J 2
(-198 3400);
DISPLAY 0.872340 (-198 3400);
PAINT GREEN (-198 3400);
DISPLAY INVISIBLE (-198 3400);
FORCEADD TAP..1
R 2
(-200 0);
FORCEPROP 3 LASTPIN (-150 0) SIG_NAME M_G_CPU0_CLK_DP<1>
J 0
(-140 10);
DISPLAY 0.659574 (-140 10);
PAINT MONO (-140 10);
DISPLAY INVISIBLE (-140 10);
FORCEPROP 1 LASTPIN (-150 0) BN 1
J 2
(-138 8);
DISPLAY 0.680851 (-138 8);
PAINT GREEN (-138 8);
FORCEPROP 2 LAST CDS_LIB standard
J 0
(-200 0);
DISPLAY INVISIBLE (-200 0);
FORCEPROP 1 LAST BODY_TYPE PLUMBING
J 2
(-200 50);
DISPLAY 0.872340 (-200 50);
PAINT GREEN (-200 50);
DISPLAY INVISIBLE (-200 50);
FORCEPROP 1 LAST HDL_TAP TRUE
J 2
(-525 -125);
DISPLAY 0.872340 (-525 -125);
DISPLAY INVISIBLE (-525 -125);
FORCEPROP 1 LAST PATH I8
J 2
(-198 0);
DISPLAY 0.872340 (-198 0);
PAINT GREEN (-198 0);
DISPLAY INVISIBLE (-198 0);
FORCEADD TAP..1
R 2
(-200 3600);
FORCEPROP 3 LASTPIN (-150 3600) SIG_NAME M_G_CPU0_SA_DQ<22>
J 0
(-140 3610);
DISPLAY 0.659574 (-140 3610);
PAINT MONO (-140 3610);
DISPLAY INVISIBLE (-140 3610);
FORCEPROP 1 LASTPIN (-150 3600) BN 22
J 2
(-138 3608);
DISPLAY 0.680851 (-138 3608);
PAINT GREEN (-138 3608);
FORCEPROP 2 LAST CDS_LIB standard
J 0
(-200 3600);
DISPLAY INVISIBLE (-200 3600);
FORCEPROP 1 LAST BODY_TYPE PLUMBING
J 2
(-200 3650);
DISPLAY 0.872340 (-200 3650);
PAINT GREEN (-200 3650);
DISPLAY INVISIBLE (-200 3650);
FORCEPROP 1 LAST HDL_TAP TRUE
J 2
(-525 3475);
DISPLAY 0.872340 (-525 3475);
DISPLAY INVISIBLE (-525 3475);
FORCEPROP 1 LAST PATH I80
J 2
(-198 3600);
DISPLAY 0.872340 (-198 3600);
PAINT GREEN (-198 3600);
DISPLAY INVISIBLE (-198 3600);
FORCEADD TAP..1
R 2
(-200 3550);
FORCEPROP 3 LASTPIN (-150 3550) SIG_NAME M_G_CPU0_SA_DQ<21>
J 0
(-140 3560);
DISPLAY 0.659574 (-140 3560);
PAINT MONO (-140 3560);
DISPLAY INVISIBLE (-140 3560);
FORCEPROP 1 LASTPIN (-150 3550) BN 21
J 2
(-138 3558);
DISPLAY 0.680851 (-138 3558);
PAINT GREEN (-138 3558);
FORCEPROP 2 LAST CDS_LIB standard
J 0
(-200 3550);
DISPLAY INVISIBLE (-200 3550);
FORCEPROP 1 LAST BODY_TYPE PLUMBING
J 2
(-200 3600);
DISPLAY 0.872340 (-200 3600);
PAINT GREEN (-200 3600);
DISPLAY INVISIBLE (-200 3600);
FORCEPROP 1 LAST HDL_TAP TRUE
J 2
(-525 3425);
DISPLAY 0.872340 (-525 3425);
DISPLAY INVISIBLE (-525 3425);
FORCEPROP 1 LAST PATH I81
J 2
(-198 3550);
DISPLAY 0.872340 (-198 3550);
PAINT GREEN (-198 3550);
DISPLAY INVISIBLE (-198 3550);
FORCEADD TAP..1
R 2
(-200 3700);
FORCEPROP 3 LASTPIN (-150 3700) SIG_NAME M_G_CPU0_SA_DQ<24>
J 0
(-140 3710);
DISPLAY 0.659574 (-140 3710);
PAINT MONO (-140 3710);
DISPLAY INVISIBLE (-140 3710);
FORCEPROP 1 LASTPIN (-150 3700) BN 24
J 2
(-138 3708);
DISPLAY 0.680851 (-138 3708);
PAINT GREEN (-138 3708);
FORCEPROP 2 LAST CDS_LIB standard
J 0
(-200 3700);
DISPLAY INVISIBLE (-200 3700);
FORCEPROP 1 LAST BODY_TYPE PLUMBING
J 2
(-200 3750);
DISPLAY 0.872340 (-200 3750);
PAINT GREEN (-200 3750);
DISPLAY INVISIBLE (-200 3750);
FORCEPROP 1 LAST HDL_TAP TRUE
J 2
(-525 3575);
DISPLAY 0.872340 (-525 3575);
DISPLAY INVISIBLE (-525 3575);
FORCEPROP 1 LAST PATH I82
J 2
(-198 3700);
DISPLAY 0.872340 (-198 3700);
PAINT GREEN (-198 3700);
DISPLAY INVISIBLE (-198 3700);
FORCEADD TAP..1
R 2
(-200 3650);
FORCEPROP 3 LASTPIN (-150 3650) SIG_NAME M_G_CPU0_SA_DQ<23>
J 0
(-140 3660);
DISPLAY 0.659574 (-140 3660);
PAINT MONO (-140 3660);
DISPLAY INVISIBLE (-140 3660);
FORCEPROP 1 LASTPIN (-150 3650) BN 23
J 2
(-138 3658);
DISPLAY 0.680851 (-138 3658);
PAINT GREEN (-138 3658);
FORCEPROP 2 LAST CDS_LIB standard
J 0
(-200 3650);
DISPLAY INVISIBLE (-200 3650);
FORCEPROP 1 LAST BODY_TYPE PLUMBING
J 2
(-200 3700);
DISPLAY 0.872340 (-200 3700);
PAINT GREEN (-200 3700);
DISPLAY INVISIBLE (-200 3700);
FORCEPROP 1 LAST HDL_TAP TRUE
J 2
(-525 3525);
DISPLAY 0.872340 (-525 3525);
DISPLAY INVISIBLE (-525 3525);
FORCEPROP 1 LAST PATH I83
J 2
(-198 3650);
DISPLAY 0.872340 (-198 3650);
PAINT GREEN (-198 3650);
DISPLAY INVISIBLE (-198 3650);
FORCEADD TAP..1
R 2
(-200 3750);
FORCEPROP 3 LASTPIN (-150 3750) SIG_NAME M_G_CPU0_SA_DQ<25>
J 0
(-140 3760);
DISPLAY 0.659574 (-140 3760);
PAINT MONO (-140 3760);
DISPLAY INVISIBLE (-140 3760);
FORCEPROP 1 LASTPIN (-150 3750) BN 25
J 2
(-138 3758);
DISPLAY 0.680851 (-138 3758);
PAINT GREEN (-138 3758);
FORCEPROP 2 LAST CDS_LIB standard
J 0
(-200 3750);
DISPLAY INVISIBLE (-200 3750);
FORCEPROP 1 LAST BODY_TYPE PLUMBING
J 2
(-200 3800);
DISPLAY 0.872340 (-200 3800);
PAINT GREEN (-200 3800);
DISPLAY INVISIBLE (-200 3800);
FORCEPROP 1 LAST HDL_TAP TRUE
J 2
(-525 3625);
DISPLAY 0.872340 (-525 3625);
DISPLAY INVISIBLE (-525 3625);
FORCEPROP 1 LAST PATH I84
J 2
(-198 3750);
DISPLAY 0.872340 (-198 3750);
PAINT GREEN (-198 3750);
DISPLAY INVISIBLE (-198 3750);
FORCEADD TAP..1
R 2
(-200 3850);
FORCEPROP 3 LASTPIN (-150 3850) SIG_NAME M_G_CPU0_SA_DQ<27>
J 0
(-140 3860);
DISPLAY 0.659574 (-140 3860);
PAINT MONO (-140 3860);
DISPLAY INVISIBLE (-140 3860);
FORCEPROP 1 LASTPIN (-150 3850) BN 27
J 2
(-138 3858);
DISPLAY 0.680851 (-138 3858);
PAINT GREEN (-138 3858);
FORCEPROP 2 LAST CDS_LIB standard
J 0
(-200 3850);
DISPLAY INVISIBLE (-200 3850);
FORCEPROP 1 LAST BODY_TYPE PLUMBING
J 2
(-200 3900);
DISPLAY 0.872340 (-200 3900);
PAINT GREEN (-200 3900);
DISPLAY INVISIBLE (-200 3900);
FORCEPROP 1 LAST HDL_TAP TRUE
J 2
(-525 3725);
DISPLAY 0.872340 (-525 3725);
DISPLAY INVISIBLE (-525 3725);
FORCEPROP 1 LAST PATH I85
J 2
(-198 3850);
DISPLAY 0.872340 (-198 3850);
PAINT GREEN (-198 3850);
DISPLAY INVISIBLE (-198 3850);
FORCEADD TAP..1
R 2
(-200 3800);
FORCEPROP 3 LASTPIN (-150 3800) SIG_NAME M_G_CPU0_SA_DQ<26>
J 0
(-140 3810);
DISPLAY 0.659574 (-140 3810);
PAINT MONO (-140 3810);
DISPLAY INVISIBLE (-140 3810);
FORCEPROP 1 LASTPIN (-150 3800) BN 26
J 2
(-138 3808);
DISPLAY 0.680851 (-138 3808);
PAINT GREEN (-138 3808);
FORCEPROP 2 LAST CDS_LIB standard
J 0
(-200 3800);
DISPLAY INVISIBLE (-200 3800);
FORCEPROP 1 LAST BODY_TYPE PLUMBING
J 2
(-200 3850);
DISPLAY 0.872340 (-200 3850);
PAINT GREEN (-200 3850);
DISPLAY INVISIBLE (-200 3850);
FORCEPROP 1 LAST HDL_TAP TRUE
J 2
(-525 3675);
DISPLAY 0.872340 (-525 3675);
DISPLAY INVISIBLE (-525 3675);
FORCEPROP 1 LAST PATH I86
J 2
(-198 3800);
DISPLAY 0.872340 (-198 3800);
PAINT GREEN (-198 3800);
DISPLAY INVISIBLE (-198 3800);
FORCEADD TAP..1
R 2
(-200 3900);
FORCEPROP 3 LASTPIN (-150 3900) SIG_NAME M_G_CPU0_SA_DQ<28>
J 0
(-140 3910);
DISPLAY 0.659574 (-140 3910);
PAINT MONO (-140 3910);
DISPLAY INVISIBLE (-140 3910);
FORCEPROP 1 LASTPIN (-150 3900) BN 28
J 2
(-138 3908);
DISPLAY 0.680851 (-138 3908);
PAINT GREEN (-138 3908);
FORCEPROP 2 LAST CDS_LIB standard
J 0
(-200 3900);
DISPLAY INVISIBLE (-200 3900);
FORCEPROP 1 LAST BODY_TYPE PLUMBING
J 2
(-200 3950);
DISPLAY 0.872340 (-200 3950);
PAINT GREEN (-200 3950);
DISPLAY INVISIBLE (-200 3950);
FORCEPROP 1 LAST HDL_TAP TRUE
J 2
(-525 3775);
DISPLAY 0.872340 (-525 3775);
DISPLAY INVISIBLE (-525 3775);
FORCEPROP 1 LAST PATH I87
J 2
(-198 3900);
DISPLAY 0.872340 (-198 3900);
PAINT GREEN (-198 3900);
DISPLAY INVISIBLE (-198 3900);
FORCEADD TAP..1
R 2
(-200 3950);
FORCEPROP 3 LASTPIN (-150 3950) SIG_NAME M_G_CPU0_SA_DQ<29>
J 0
(-140 3960);
DISPLAY 0.659574 (-140 3960);
PAINT MONO (-140 3960);
DISPLAY INVISIBLE (-140 3960);
FORCEPROP 1 LASTPIN (-150 3950) BN 29
J 2
(-138 3958);
DISPLAY 0.680851 (-138 3958);
PAINT GREEN (-138 3958);
FORCEPROP 2 LAST CDS_LIB standard
J 0
(-200 3950);
DISPLAY INVISIBLE (-200 3950);
FORCEPROP 1 LAST BODY_TYPE PLUMBING
J 2
(-200 4000);
DISPLAY 0.872340 (-200 4000);
PAINT GREEN (-200 4000);
DISPLAY INVISIBLE (-200 4000);
FORCEPROP 1 LAST HDL_TAP TRUE
J 2
(-525 3825);
DISPLAY 0.872340 (-525 3825);
DISPLAY INVISIBLE (-525 3825);
FORCEPROP 1 LAST PATH I88
J 2
(-198 3950);
DISPLAY 0.872340 (-198 3950);
PAINT GREEN (-198 3950);
DISPLAY INVISIBLE (-198 3950);
FORCEADD TAP..1
R 2
(-200 4000);
FORCEPROP 3 LASTPIN (-150 4000) SIG_NAME M_G_CPU0_SA_DQ<30>
J 0
(-140 4010);
DISPLAY 0.659574 (-140 4010);
PAINT MONO (-140 4010);
DISPLAY INVISIBLE (-140 4010);
FORCEPROP 1 LASTPIN (-150 4000) BN 30
J 2
(-138 4008);
DISPLAY 0.680851 (-138 4008);
PAINT GREEN (-138 4008);
FORCEPROP 2 LAST CDS_LIB standard
J 0
(-200 4000);
DISPLAY INVISIBLE (-200 4000);
FORCEPROP 1 LAST BODY_TYPE PLUMBING
J 2
(-200 4050);
DISPLAY 0.872340 (-200 4050);
PAINT GREEN (-200 4050);
DISPLAY INVISIBLE (-200 4050);
FORCEPROP 1 LAST HDL_TAP TRUE
J 2
(-525 3875);
DISPLAY 0.872340 (-525 3875);
DISPLAY INVISIBLE (-525 3875);
FORCEPROP 1 LAST PATH I89
J 2
(-198 4000);
DISPLAY 0.872340 (-198 4000);
PAINT GREEN (-198 4000);
DISPLAY INVISIBLE (-198 4000);
FORCEADD TAP..1
R 2
(-200 200);
FORCEPROP 3 LASTPIN (-150 200) SIG_NAME M_G_CPU0_SB_CB<2>
J 0
(-140 210);
DISPLAY 0.659574 (-140 210);
PAINT MONO (-140 210);
DISPLAY INVISIBLE (-140 210);
FORCEPROP 1 LASTPIN (-150 200) BN 2
J 2
(-138 208);
DISPLAY 0.680851 (-138 208);
PAINT GREEN (-138 208);
FORCEPROP 2 LAST CDS_LIB standard
J 0
(-200 200);
DISPLAY INVISIBLE (-200 200);
FORCEPROP 1 LAST BODY_TYPE PLUMBING
J 2
(-200 250);
DISPLAY 0.872340 (-200 250);
PAINT GREEN (-200 250);
DISPLAY INVISIBLE (-200 250);
FORCEPROP 1 LAST HDL_TAP TRUE
J 2
(-525 75);
DISPLAY 0.872340 (-525 75);
DISPLAY INVISIBLE (-525 75);
FORCEPROP 1 LAST PATH I9
J 2
(-198 200);
DISPLAY 0.872340 (-198 200);
PAINT GREEN (-198 200);
DISPLAY INVISIBLE (-198 200);
FORCEADD TAP..1
R 2
(-200 4050);
FORCEPROP 3 LASTPIN (-150 4050) SIG_NAME M_G_CPU0_SA_DQ<31>
J 0
(-140 4060);
DISPLAY 0.659574 (-140 4060);
PAINT MONO (-140 4060);
DISPLAY INVISIBLE (-140 4060);
FORCEPROP 1 LASTPIN (-150 4050) BN 31
J 2
(-138 4058);
DISPLAY 0.680851 (-138 4058);
PAINT GREEN (-138 4058);
FORCEPROP 2 LAST CDS_LIB standard
J 0
(-200 4050);
DISPLAY INVISIBLE (-200 4050);
FORCEPROP 1 LAST BODY_TYPE PLUMBING
J 2
(-200 4100);
DISPLAY 0.872340 (-200 4100);
PAINT GREEN (-200 4100);
DISPLAY INVISIBLE (-200 4100);
FORCEPROP 1 LAST HDL_TAP TRUE
J 2
(-525 3925);
DISPLAY 0.872340 (-525 3925);
DISPLAY INVISIBLE (-525 3925);
FORCEPROP 1 LAST PATH I90
J 2
(-198 4050);
DISPLAY 0.872340 (-198 4050);
PAINT GREEN (-198 4050);
DISPLAY INVISIBLE (-198 4050);
FORCEADD OFFPAGE..4
(4325 -150);
FORCEPROP 2 LAST $XR1 95 
J 0
(4601 -150);
DISPLAY 0.638298 (4601 -150);
PAINT MONO (4601 -150);
FORCEPROP 2 LAST $XR0 94 
J 0
(4511 -150);
DISPLAY 0.638298 (4511 -150);
PAINT MONO (4511 -150);
FORCEPROP 2 LAST CDS_LIB standard
J 0
(4325 -150);
PAINT MONO (4325 -150);
DISPLAY INVISIBLE (4325 -150);
FORCEPROP 1 LAST OFFPAGE TRUE
J 0
(4650 -275);
DISPLAY 1.170213 (4650 -275);
PAINT GREEN (4650 -275);
DISPLAY INVISIBLE (4650 -275);
FORCEPROP 1 LAST COMMENT_BODY TRUE
J 0
(4300 -250);
DISPLAY 1.170213 (4300 -250);
PAINT GREEN (4300 -250);
DISPLAY INVISIBLE (4300 -250);
FORCEPROP 2 LAST PATH I92
J 0
(4500 -75);
DISPLAY 1.021277 (4500 -75);
DISPLAY INVISIBLE (4500 -75);
FORCEADD OFFPAGE..4
(4325 -50);
FORCEPROP 2 LAST $XR0 94 
J 0
(4511 -50);
DISPLAY 0.638298 (4511 -50);
PAINT MONO (4511 -50);
FORCEPROP 2 LAST CDS_LIB standard
J 0
(4325 -50);
PAINT MONO (4325 -50);
DISPLAY INVISIBLE (4325 -50);
FORCEPROP 1 LAST OFFPAGE TRUE
J 0
(4650 -175);
DISPLAY 1.170213 (4650 -175);
PAINT GREEN (4650 -175);
DISPLAY INVISIBLE (4650 -175);
FORCEPROP 1 LAST COMMENT_BODY TRUE
J 0
(4300 -150);
DISPLAY 1.170213 (4300 -150);
PAINT GREEN (4300 -150);
DISPLAY INVISIBLE (4300 -150);
FORCEPROP 2 LAST PATH I93
J 0
(4500 25);
DISPLAY 1.021277 (4500 25);
DISPLAY INVISIBLE (4500 25);
FORCEADD OFFPAGE..4
(4325 0);
FORCEPROP 2 LAST $XR0 95 
J 0
(4511 0);
DISPLAY 0.638298 (4511 0);
PAINT MONO (4511 0);
FORCEPROP 2 LAST CDS_LIB standard
J 0
(4325 0);
PAINT MONO (4325 0);
DISPLAY INVISIBLE (4325 0);
FORCEPROP 1 LAST OFFPAGE TRUE
J 0
(4650 -125);
DISPLAY 1.170213 (4650 -125);
PAINT GREEN (4650 -125);
DISPLAY INVISIBLE (4650 -125);
FORCEPROP 1 LAST COMMENT_BODY TRUE
J 0
(4300 -100);
DISPLAY 1.170213 (4300 -100);
PAINT GREEN (4300 -100);
DISPLAY INVISIBLE (4300 -100);
FORCEPROP 2 LAST PATH I94
J 0
(4500 75);
DISPLAY 1.021277 (4500 75);
DISPLAY INVISIBLE (4500 75);
FORCEADD OFFPAGE..4
(4325 100);
FORCEPROP 2 LAST $XR0 94 
J 0
(4511 100);
DISPLAY 0.638298 (4511 100);
PAINT MONO (4511 100);
FORCEPROP 2 LAST CDS_LIB standard
J 0
(4325 100);
PAINT MONO (4325 100);
DISPLAY INVISIBLE (4325 100);
FORCEPROP 1 LAST OFFPAGE TRUE
J 0
(4650 -25);
DISPLAY 1.170213 (4650 -25);
PAINT GREEN (4650 -25);
DISPLAY INVISIBLE (4650 -25);
FORCEPROP 1 LAST COMMENT_BODY TRUE
J 0
(4300 0);
DISPLAY 1.170213 (4300 0);
PAINT GREEN (4300 0);
DISPLAY INVISIBLE (4300 0);
FORCEPROP 2 LAST PATH I95
J 0
(4500 175);
DISPLAY 1.021277 (4500 175);
DISPLAY INVISIBLE (4500 175);
FORCEADD OFFPAGE..4
(4325 150);
FORCEPROP 2 LAST $XR0 95 
J 0
(4511 150);
DISPLAY 0.638298 (4511 150);
PAINT MONO (4511 150);
FORCEPROP 2 LAST CDS_LIB standard
J 0
(4325 150);
PAINT MONO (4325 150);
DISPLAY INVISIBLE (4325 150);
FORCEPROP 1 LAST OFFPAGE TRUE
J 0
(4650 25);
DISPLAY 1.170213 (4650 25);
PAINT GREEN (4650 25);
DISPLAY INVISIBLE (4650 25);
FORCEPROP 1 LAST COMMENT_BODY TRUE
J 0
(4300 50);
DISPLAY 1.170213 (4300 50);
PAINT GREEN (4300 50);
DISPLAY INVISIBLE (4300 50);
FORCEPROP 2 LAST PATH I96
J 0
(4500 225);
DISPLAY 1.021277 (4500 225);
DISPLAY INVISIBLE (4500 225);
FORCEADD TAP..1
(3225 300);
FORCEPROP 3 LASTPIN (3175 300) SIG_NAME M_G_CPU0_SB_CS_N<0>
J 0
(3185 310);
DISPLAY 0.659574 (3185 310);
PAINT MONO (3185 310);
DISPLAY INVISIBLE (3185 310);
FORCEPROP 1 LASTPIN (3175 300) BN 0
J 0
(3163 308);
DISPLAY 0.680851 (3163 308);
PAINT GREEN (3163 308);
FORCEPROP 2 LAST CDS_LIB standard
J 0
(3225 300);
DISPLAY INVISIBLE (3225 300);
FORCEPROP 1 LAST BODY_TYPE PLUMBING
J 0
(3225 350);
DISPLAY 0.872340 (3225 350);
PAINT GREEN (3225 350);
DISPLAY INVISIBLE (3225 350);
FORCEPROP 1 LAST HDL_TAP TRUE
J 0
(3550 175);
DISPLAY 0.872340 (3550 175);
DISPLAY INVISIBLE (3550 175);
FORCEPROP 1 LAST PATH I97
J 0
(3223 300);
DISPLAY 0.872340 (3223 300);
PAINT GREEN (3223 300);
DISPLAY INVISIBLE (3223 300);
FORCEADD TAP..1
(3225 450);
FORCEPROP 3 LASTPIN (3175 450) SIG_NAME M_G_CPU0_SB_CS_N<3>
J 0
(3185 460);
DISPLAY 0.659574 (3185 460);
PAINT MONO (3185 460);
DISPLAY INVISIBLE (3185 460);
FORCEPROP 1 LASTPIN (3175 450) BN 3
J 0
(3163 458);
DISPLAY 0.680851 (3163 458);
PAINT GREEN (3163 458);
FORCEPROP 2 LAST CDS_LIB standard
J 0
(3225 450);
DISPLAY INVISIBLE (3225 450);
FORCEPROP 1 LAST BODY_TYPE PLUMBING
J 0
(3225 500);
DISPLAY 0.872340 (3225 500);
PAINT GREEN (3225 500);
DISPLAY INVISIBLE (3225 500);
FORCEPROP 1 LAST HDL_TAP TRUE
J 0
(3550 325);
DISPLAY 0.872340 (3550 325);
DISPLAY INVISIBLE (3550 325);
FORCEPROP 1 LAST PATH I98
J 0
(3223 450);
DISPLAY 0.872340 (3223 450);
PAINT GREEN (3223 450);
DISPLAY INVISIBLE (3223 450);
FORCEADD TAP..1
(3225 350);
FORCEPROP 3 LASTPIN (3175 350) SIG_NAME M_G_CPU0_SB_CS_N<1>
J 0
(3185 360);
DISPLAY 0.659574 (3185 360);
PAINT MONO (3185 360);
DISPLAY INVISIBLE (3185 360);
FORCEPROP 1 LASTPIN (3175 350) BN 1
J 0
(3163 358);
DISPLAY 0.680851 (3163 358);
PAINT GREEN (3163 358);
FORCEPROP 2 LAST CDS_LIB standard
J 0
(3225 350);
DISPLAY INVISIBLE (3225 350);
FORCEPROP 1 LAST BODY_TYPE PLUMBING
J 0
(3225 400);
DISPLAY 0.872340 (3225 400);
PAINT GREEN (3225 400);
DISPLAY INVISIBLE (3225 400);
FORCEPROP 1 LAST HDL_TAP TRUE
J 0
(3550 225);
DISPLAY 0.872340 (3550 225);
DISPLAY INVISIBLE (3550 225);
FORCEPROP 1 LAST PATH I99
J 0
(3223 350);
DISPLAY 0.872340 (3223 350);
PAINT GREEN (3223 350);
DISPLAY INVISIBLE (3223 350);
FORCEADD QUANTA_TITLE_BLOCK_C..1
(6150 -1450);
FORCEPROP 0 LAST CDS_CON_LAST_MODIFIED Fri Aug 25 14:00:11 2023
J 0
(4265 -1435);
PAINT MONO (4265 -1435);
DISPLAY INVISIBLE (4265 -1435);
FORCEPROP 1 LAST CUSTOM_TXT_CDS <CON_LAST_MODIFIED>
J 0
(4265 -1435);
DISPLAY 0.978723 (4265 -1435);
FORCEPROP 2 LAST CUSTOM_TXT_CDS <XR_PAGE_TITLE>
J 0
(-1740 3800);
DISPLAY 0.638298 (-1740 3800);
PAINT PINK (-1740 3800);
DISPLAY INVISIBLE (-1740 3800);
FORCEPROP 2 LAST CUSTOM_TXT_CDS <Q_NUMBER>
J 0
(4747 -1347);
DISPLAY 1.212766 (4747 -1347);
FORCEPROP 2 LAST CUSTOM_TXT_CDS 01
J 0
(5966 -1347);
DISPLAY 1.212766 (5966 -1347);
FORCEPROP 1 LAST CUSTOM_TXT_CDS <NAME_2>
J 0
(2975 -1400);
FORCEPROP 1 LAST CUSTOM_TXT_CDS <NAME_1>
J 0
(2975 -1275);
FORCEPROP 1 LAST CUSTOM_TXT_CDS <Q_PROJ>
J 0
(3768 -1348);
DISPLAY 1.212766 (3768 -1348);
FORCEPROP 1 LAST CUSTOM_TXT_CDS <Q_REV>
J 0
(5966 -1347);
DISPLAY 1.212766 (5966 -1347);
FORCEPROP 1 LAST CUSTOM_TXT_CDS <CON_PAGE_NUM> OF <CON_TOTAL_PAGES>
J 0
(5704 -1432);
DISPLAY 0.978723 (5704 -1432);
FORCEPROP 1 LAST Q_TITLE SPR CPU0 - DDR CH G (14 OF 30)
J 0
(-3216 -1424);
DISPLAY 1.957447 (-3216 -1424);
PAINT GREEN (-3216 -1424);
FORCEPROP 1 LAST Q_DEPT 
J 1
(2387 -1401);
DISPLAY 1.957447 (2387 -1401);
PAINT GREEN (2387 -1401);
FORCEPROP 2 LAST PAGE_BORDER TRUE
J 0
(-1740 3800);
DISPLAY 0.638298 (-1740 3800);
PAINT PINK (-1740 3800);
DISPLAY INVISIBLE (-1740 3800);
FORCEPROP 1 LAST CDS_LMAN_SYM_OUTLINE -9475,6775,100,-125
J 0
(6150 -1450);
DISPLAY 0.468085 (6150 -1450);
PAINT GREEN (6150 -1450);
DISPLAY INVISIBLE (6150 -1450);
FORCEPROP 2 LAST CDS_LIB pure_quanta
J 0
(6150 -1450);
PAINT MONO (6150 -1450);
DISPLAY INVISIBLE (6150 -1450);
FORCEPROP 2 LAST CDS_XR_PAGE_TITLE CR-26 : @S9S_MB_2U_LIB.S9S_MB_2U(SCH_1):PAGE26
J 0
(-1740 3800);
DISPLAY 0.638298 (-1740 3800);
PAINT PINK (-1740 3800);
DISPLAY INVISIBLE (-1740 3800);
FORCEPROP 1 LAST COMMENT_BODY TRUE
J 0
(6162 -1463);
DISPLAY 0.978723 (6162 -1463);
PAINT GREEN (6162 -1463);
DISPLAY INVISIBLE (6162 -1463);
WIRE 17 -1 (3275 1725)(3275 1775);
WIRE 17 -1 (3275 1675)(3275 1725);
WIRE 17 -1 (3275 1775)(4275 1775);
FORCEPROP 2 LAST SIG_NAME M_G_CPU0_SA_CA<6:0>
J 0
(3415 1785);
DISPLAY 0.680851 (3415 1785);
PAINT WHITE (3415 1785);
WIRE 17 -1 (3275 1625)(3275 1675);
WIRE 17 -1 (3275 1575)(3275 1625);
WIRE 17 -1 (3275 1525)(3275 1575);
WIRE 17 -1 (3275 1475)(3275 1525);
WIRE 17 -1 (3275 725)(3275 775);
WIRE 17 -1 (3275 675)(3275 725);
WIRE 17 -1 (3275 775)(4275 775);
FORCEPROP 2 LAST SIG_NAME M_G_CPU0_SA_CS_N<3:0>
J 0
(3415 785);
DISPLAY 0.680851 (3415 785);
PAINT WHITE (3415 785);
WIRE 17 -1 (3275 625)(3275 675);
WIRE 17 -1 (3275 3475)(3275 3525);
WIRE 17 -1 (3275 3425)(3275 3475);
WIRE 17 -1 (3275 3525)(4275 3525);
FORCEPROP 2 LAST SIG_NAME M_G_CPU0_SA_DQS_DN<9:0>
J 0
(3415 3535);
DISPLAY 0.680851 (3415 3535);
PAINT WHITE (3415 3535);
WIRE 17 -1 (3275 3375)(3275 3425);
WIRE 17 -1 (3275 3325)(3275 3375);
WIRE 17 -1 (3275 3275)(3275 3325);
WIRE 17 -1 (3275 3225)(3275 3275);
WIRE 17 -1 (3275 3175)(3275 3225);
WIRE 17 -1 (3275 3125)(3275 3175);
WIRE 17 -1 (3275 3075)(3275 3125);
WIRE 17 -1 (3275 4025)(3275 4075);
WIRE 17 -1 (3275 3975)(3275 4025);
WIRE 17 -1 (3275 4075)(4275 4075);
FORCEPROP 2 LAST SIG_NAME M_G_CPU0_SA_DQS_DP<9:0>
J 0
(3415 4085);
DISPLAY 0.680851 (3415 4085);
PAINT WHITE (3415 4085);
WIRE 17 -1 (3275 3925)(3275 3975);
WIRE 17 -1 (3275 3875)(3275 3925);
WIRE 17 -1 (3275 3825)(3275 3875);
WIRE 17 -1 (3275 3775)(3275 3825);
WIRE 17 -1 (3275 3725)(3275 3775);
WIRE 17 -1 (3275 3675)(3275 3725);
WIRE 17 -1 (3275 3625)(3275 3675);
WIRE 17 -1 (3275 1225)(3275 1275);
WIRE 17 -1 (3275 1175)(3275 1225);
WIRE 17 -1 (3275 1275)(4275 1275);
FORCEPROP 2 LAST SIG_NAME M_G_CPU0_SB_CA<6:0>
J 0
(3415 1285);
DISPLAY 0.680851 (3415 1285);
PAINT WHITE (3415 1285);
WIRE 17 -1 (3275 1125)(3275 1175);
WIRE 17 -1 (3275 1075)(3275 1125);
WIRE 17 -1 (3275 1025)(3275 1075);
WIRE 17 -1 (3275 975)(3275 1025);
WIRE 17 -1 (3275 425)(3275 475);
WIRE 17 -1 (3275 375)(3275 425);
WIRE 17 -1 (3275 475)(4275 475);
FORCEPROP 2 LAST SIG_NAME M_G_CPU0_SB_CS_N<3:0>
J 0
(3415 485);
DISPLAY 0.680851 (3415 485);
PAINT WHITE (3415 485);
WIRE 17 -1 (3275 325)(3275 375);
WIRE 17 -1 (3275 2325)(3275 2375);
WIRE 17 -1 (3275 2275)(3275 2325);
WIRE 17 -1 (3275 2375)(4275 2375);
FORCEPROP 2 LAST SIG_NAME M_G_CPU0_SB_DQS_DN<9:0>
J 0
(3415 2385);
DISPLAY 0.680851 (3415 2385);
PAINT WHITE (3415 2385);
WIRE 17 -1 (3275 2225)(3275 2275);
WIRE 17 -1 (3275 2175)(3275 2225);
WIRE 17 -1 (3275 2125)(3275 2175);
WIRE 17 -1 (3275 2075)(3275 2125);
WIRE 17 -1 (3275 2025)(3275 2075);
WIRE 17 -1 (3275 1975)(3275 2025);
WIRE 17 -1 (3275 1925)(3275 1975);
WIRE 17 -1 (3275 2875)(3275 2925);
WIRE 17 -1 (3275 2825)(3275 2875);
WIRE 17 -1 (3275 2925)(4275 2925);
FORCEPROP 2 LAST SIG_NAME M_G_CPU0_SB_DQS_DP<9:0>
J 0
(3415 2935);
DISPLAY 0.680851 (3415 2935);
PAINT WHITE (3415 2935);
WIRE 17 -1 (3275 2775)(3275 2825);
WIRE 17 -1 (3275 2725)(3275 2775);
WIRE 17 -1 (3275 2675)(3275 2725);
WIRE 17 -1 (3275 2625)(3275 2675);
WIRE 17 -1 (3275 2575)(3275 2625);
WIRE 17 -1 (3275 2525)(3275 2575);
WIRE 17 -1 (3275 2475)(3275 2525);
WIRE 17 -1 (-250 125)(-250 175);
WIRE 17 -1 (-250 175)(-250 225);
WIRE 17 -1 (-250 225)(-250 275);
WIRE 17 -1 (-250 275)(-250 325);
WIRE 17 -1 (-250 325)(-250 375);
WIRE 17 -1 (-250 375)(-250 425);
WIRE 17 -1 (-250 425)(-250 475);
WIRE 17 -1 (-1175 475)(-250 475);
FORCEPROP 2 LAST SIG_NAME M_G_CPU0_SB_CB<7:0>
J 0
(-1035 485);
DISPLAY 0.680851 (-1035 485);
PAINT WHITE (-1035 485);
WIRE 17 -1 (-250 525)(-250 575);
WIRE 17 -1 (-250 575)(-250 625);
WIRE 17 -1 (-250 625)(-250 675);
WIRE 17 -1 (-250 675)(-250 725);
WIRE 17 -1 (-250 725)(-250 775);
WIRE 17 -1 (-250 775)(-250 825);
WIRE 17 -1 (-250 825)(-250 875);
WIRE 17 -1 (-250 875)(-250 925);
WIRE 17 -1 (-250 925)(-250 975);
WIRE 17 -1 (-250 975)(-250 1025);
WIRE 17 -1 (-250 1025)(-250 1075);
WIRE 17 -1 (-250 1075)(-250 1125);
WIRE 17 -1 (-250 1125)(-250 1175);
WIRE 17 -1 (-250 1175)(-250 1225);
WIRE 17 -1 (-250 1225)(-250 1275);
WIRE 17 -1 (-250 1275)(-250 1325);
WIRE 17 -1 (-250 1325)(-250 1375);
WIRE 17 -1 (-250 1375)(-250 1425);
WIRE 17 -1 (-250 1425)(-250 1475);
WIRE 17 -1 (-250 1475)(-250 1525);
WIRE 17 -1 (-250 1525)(-250 1575);
WIRE 17 -1 (-250 1575)(-250 1625);
WIRE 17 -1 (-250 1625)(-250 1675);
WIRE 17 -1 (-250 1675)(-250 1725);
WIRE 17 -1 (-250 1725)(-250 1775);
WIRE 17 -1 (-250 1775)(-250 1825);
WIRE 17 -1 (-250 1825)(-250 1875);
WIRE 17 -1 (-250 1875)(-250 1925);
WIRE 17 -1 (-250 1925)(-250 1975);
WIRE 17 -1 (-250 1975)(-250 2025);
WIRE 17 -1 (-250 2025)(-250 2075);
WIRE 17 -1 (-1175 2075)(-250 2075);
FORCEPROP 2 LAST SIG_NAME M_G_CPU0_SB_DQ<31:0>
J 0
(-1035 2085);
DISPLAY 0.680851 (-1035 2085);
PAINT WHITE (-1035 2085);
WIRE 17 -1 (-250 2125)(-250 2175);
WIRE 17 -1 (-250 2175)(-250 2225);
WIRE 17 -1 (-250 2225)(-250 2275);
WIRE 17 -1 (-250 2275)(-250 2325);
WIRE 17 -1 (-250 2325)(-250 2375);
WIRE 17 -1 (-250 2375)(-250 2425);
WIRE 17 -1 (-250 2425)(-250 2475);
WIRE 17 -1 (-1175 2475)(-250 2475);
FORCEPROP 2 LAST SIG_NAME M_G_CPU0_SA_CB<7:0>
J 0
(-1035 2485);
DISPLAY 0.680851 (-1035 2485);
PAINT WHITE (-1035 2485);
WIRE 17 -1 (-250 2525)(-250 2575);
WIRE 17 -1 (-250 2575)(-250 2625);
WIRE 17 -1 (-250 2625)(-250 2675);
WIRE 17 -1 (-250 2675)(-250 2725);
WIRE 17 -1 (-250 2725)(-250 2775);
WIRE 17 -1 (-250 2775)(-250 2825);
WIRE 17 -1 (-250 2825)(-250 2875);
WIRE 17 -1 (-250 2875)(-250 2925);
WIRE 17 -1 (-250 2925)(-250 2975);
WIRE 17 -1 (-250 2975)(-250 3025);
WIRE 17 -1 (-250 3025)(-250 3075);
WIRE 17 -1 (-250 3075)(-250 3125);
WIRE 17 -1 (-250 3125)(-250 3175);
WIRE 17 -1 (-250 3175)(-250 3225);
WIRE 17 -1 (-250 3225)(-250 3275);
WIRE 17 -1 (-250 3275)(-250 3325);
WIRE 17 -1 (-250 3325)(-250 3375);
WIRE 17 -1 (-250 3375)(-250 3425);
WIRE 17 -1 (-250 3425)(-250 3475);
WIRE 17 -1 (-250 3475)(-250 3525);
WIRE 17 -1 (-250 3525)(-250 3575);
WIRE 17 -1 (-250 3575)(-250 3625);
WIRE 17 -1 (-250 3625)(-250 3675);
WIRE 17 -1 (-250 3675)(-250 3725);
WIRE 17 -1 (-250 3725)(-250 3775);
WIRE 17 -1 (-250 3775)(-250 3825);
WIRE 17 -1 (-250 3825)(-250 3875);
WIRE 17 -1 (-250 3875)(-250 3925);
WIRE 17 -1 (-250 3925)(-250 3975);
WIRE 17 -1 (-250 3975)(-250 4025);
WIRE 17 -1 (-250 4025)(-250 4075);
WIRE 17 -1 (-1175 4075)(-250 4075);
FORCEPROP 2 LAST SIG_NAME M_G_CPU0_SA_DQ<31:0>
J 0
(-1035 4085);
DISPLAY 0.680851 (-1035 4085);
PAINT WHITE (-1035 4085);
WIRE 17 -1 (-250 -25)(-250 25);
WIRE 17 -1 (-1175 25)(-250 25);
FORCEPROP 2 LAST SIG_NAME M_G_CPU0_CLK_DP<1:0>
J 0
(-1035 35);
DISPLAY 0.680851 (-1035 35);
PAINT WHITE (-1035 35);
WIRE 17 -1 (-250 -125)(-250 -75);
WIRE 17 -1 (-1175 -75)(-250 -75);
FORCEPROP 2 LAST SIG_NAME M_G_CPU0_CLK_DN<1:0>
J 0
(-1035 -65);
DISPLAY 0.680851 (-1035 -65);
PAINT WHITE (-1035 -65);
WIRE 16 -1 (-150 -100)(300 -100);
WIRE 16 -1 (-150 -150)(300 -150);
WIRE 16 -1 (-150 0)(300 0);
WIRE 16 -1 (-150 -50)(300 -50);
WIRE 16 -1 (-150 4050)(300 4050);
WIRE 16 -1 (-150 4000)(300 4000);
WIRE 16 -1 (-150 3950)(300 3950);
WIRE 16 -1 (-150 3900)(300 3900);
WIRE 16 -1 (-150 3850)(300 3850);
WIRE 16 -1 (-150 3800)(300 3800);
WIRE 16 -1 (-150 3750)(300 3750);
WIRE 16 -1 (-150 3700)(300 3700);
WIRE 16 -1 (-150 3650)(300 3650);
WIRE 16 -1 (-150 3600)(300 3600);
WIRE 16 -1 (-150 3550)(300 3550);
WIRE 16 -1 (-150 3500)(300 3500);
WIRE 16 -1 (-150 3450)(300 3450);
WIRE 16 -1 (-150 3400)(300 3400);
WIRE 16 -1 (-150 3350)(300 3350);
WIRE 16 -1 (-150 3300)(300 3300);
WIRE 16 -1 (-150 3250)(300 3250);
WIRE 16 -1 (-150 3200)(300 3200);
WIRE 16 -1 (-150 3150)(300 3150);
WIRE 16 -1 (-150 3100)(300 3100);
WIRE 16 -1 (-150 3050)(300 3050);
WIRE 16 -1 (-150 3000)(300 3000);
WIRE 16 -1 (-150 2950)(300 2950);
WIRE 16 -1 (-150 2900)(300 2900);
WIRE 16 -1 (-150 2850)(300 2850);
WIRE 16 -1 (-150 2800)(300 2800);
WIRE 16 -1 (-150 2750)(300 2750);
WIRE 16 -1 (-150 2700)(300 2700);
WIRE 16 -1 (-150 2650)(300 2650);
WIRE 16 -1 (-150 2600)(300 2600);
WIRE 16 -1 (-150 2550)(300 2550);
WIRE 16 -1 (-150 2500)(300 2500);
WIRE 16 -1 (-150 2450)(300 2450);
WIRE 16 -1 (-150 2400)(300 2400);
WIRE 16 -1 (-150 2350)(300 2350);
WIRE 16 -1 (-150 2300)(300 2300);
WIRE 16 -1 (-150 2250)(300 2250);
WIRE 16 -1 (-150 2200)(300 2200);
WIRE 16 -1 (-150 2150)(300 2150);
WIRE 16 -1 (-150 2100)(300 2100);
WIRE 16 -1 (-150 2050)(300 2050);
WIRE 16 -1 (-150 2000)(300 2000);
WIRE 16 -1 (-150 1950)(300 1950);
WIRE 16 -1 (-150 1900)(300 1900);
WIRE 16 -1 (-150 1850)(300 1850);
WIRE 16 -1 (-150 1800)(300 1800);
WIRE 16 -1 (-150 1750)(300 1750);
WIRE 16 -1 (-150 1700)(300 1700);
WIRE 16 -1 (-150 1650)(300 1650);
WIRE 16 -1 (-150 1600)(300 1600);
WIRE 16 -1 (-150 1550)(300 1550);
WIRE 16 -1 (-150 1500)(300 1500);
WIRE 16 -1 (-150 1450)(300 1450);
WIRE 16 -1 (-150 1400)(300 1400);
WIRE 16 -1 (-150 1350)(300 1350);
WIRE 16 -1 (-150 1300)(300 1300);
WIRE 16 -1 (-150 1250)(300 1250);
WIRE 16 -1 (-150 1200)(300 1200);
WIRE 16 -1 (-150 1150)(300 1150);
WIRE 16 -1 (-150 1100)(300 1100);
WIRE 16 -1 (-150 1050)(300 1050);
WIRE 16 -1 (-150 1000)(300 1000);
WIRE 16 -1 (-150 950)(300 950);
WIRE 16 -1 (-150 900)(300 900);
WIRE 16 -1 (-150 850)(300 850);
WIRE 16 -1 (-150 800)(300 800);
WIRE 16 -1 (-150 750)(300 750);
WIRE 16 -1 (-150 700)(300 700);
WIRE 16 -1 (-150 650)(300 650);
WIRE 16 -1 (-150 600)(300 600);
WIRE 16 -1 (-150 550)(300 550);
WIRE 16 -1 (-150 500)(300 500);
WIRE 16 -1 (-150 450)(300 450);
WIRE 16 -1 (-150 400)(300 400);
WIRE 16 -1 (-150 350)(300 350);
WIRE 16 -1 (-150 300)(300 300);
WIRE 16 -1 (-150 250)(300 250);
WIRE 16 -1 (-150 200)(300 200);
WIRE 16 -1 (-150 150)(300 150);
WIRE 16 -1 (-150 100)(300 100);
WIRE 16 -1 (4275 900)(2750 900);
FORCEPROP 2 LAST SIG_NAME M_G_CPU0_SB_PAR
J 0
(3384 909);
DISPLAY 0.680851 (3384 909);
PAINT WHITE (3384 909);
WIRE 16 -1 (2750 2450)(3175 2450);
WIRE 16 -1 (2750 2500)(3175 2500);
WIRE 16 -1 (2750 2550)(3175 2550);
WIRE 16 -1 (2750 2600)(3175 2600);
WIRE 16 -1 (2750 2650)(3175 2650);
WIRE 16 -1 (2750 2700)(3175 2700);
WIRE 16 -1 (2750 2750)(3175 2750);
WIRE 16 -1 (2750 2800)(3175 2800);
WIRE 16 -1 (2750 2850)(3175 2850);
WIRE 16 -1 (2750 2900)(3175 2900);
WIRE 16 -1 (2750 1900)(3175 1900);
WIRE 16 -1 (2750 1950)(3175 1950);
WIRE 16 -1 (2750 2000)(3175 2000);
WIRE 16 -1 (2750 2050)(3175 2050);
WIRE 16 -1 (2750 2100)(3175 2100);
WIRE 16 -1 (2750 2150)(3175 2150);
WIRE 16 -1 (2750 2200)(3175 2200);
WIRE 16 -1 (2750 2250)(3175 2250);
WIRE 16 -1 (2750 2300)(3175 2300);
WIRE 16 -1 (2750 2350)(3175 2350);
WIRE 16 -1 (2750 300)(3175 300);
WIRE 16 -1 (2750 350)(3175 350);
WIRE 16 -1 (2750 400)(3175 400);
WIRE 16 -1 (2750 450)(3175 450);
WIRE 16 -1 (2750 950)(3175 950);
WIRE 16 -1 (2750 1000)(3175 1000);
WIRE 16 -1 (2750 1050)(3175 1050);
WIRE 16 -1 (2750 1100)(3175 1100);
WIRE 16 -1 (2750 1150)(3175 1150);
WIRE 16 -1 (2750 1200)(3175 1200);
WIRE 16 -1 (2750 1250)(3175 1250);
WIRE 16 -1 (4275 1400)(2750 1400);
FORCEPROP 2 LAST SIG_NAME M_G_CPU0_SA_PAR
J 0
(3384 1409);
DISPLAY 0.680851 (3384 1409);
PAINT WHITE (3384 1409);
WIRE 16 -1 (2750 3600)(3175 3600);
WIRE 16 -1 (2750 3650)(3175 3650);
WIRE 16 -1 (2750 3700)(3175 3700);
WIRE 16 -1 (2750 3750)(3175 3750);
WIRE 16 -1 (2750 3800)(3175 3800);
WIRE 16 -1 (2750 3850)(3175 3850);
WIRE 16 -1 (2750 3900)(3175 3900);
WIRE 16 -1 (2750 3950)(3175 3950);
WIRE 16 -1 (2750 4000)(3175 4000);
WIRE 16 -1 (2750 4050)(3175 4050);
WIRE 16 -1 (2750 3050)(3175 3050);
WIRE 16 -1 (2750 3100)(3175 3100);
WIRE 16 -1 (2750 3150)(3175 3150);
WIRE 16 -1 (2750 3200)(3175 3200);
WIRE 16 -1 (2750 3250)(3175 3250);
WIRE 16 -1 (2750 3300)(3175 3300);
WIRE 16 -1 (2750 3350)(3175 3350);
WIRE 16 -1 (2750 3400)(3175 3400);
WIRE 16 -1 (2750 3450)(3175 3450);
WIRE 16 -1 (2750 3500)(3175 3500);
WIRE 16 -1 (2750 600)(3175 600);
WIRE 16 -1 (2750 650)(3175 650);
WIRE 16 -1 (2750 700)(3175 700);
WIRE 16 -1 (2750 750)(3175 750);
WIRE 16 -1 (2750 1450)(3175 1450);
WIRE 16 -1 (2750 1500)(3175 1500);
WIRE 16 -1 (2750 1550)(3175 1550);
WIRE 16 -1 (2750 1600)(3175 1600);
WIRE 16 -1 (2750 1650)(3175 1650);
WIRE 16 -1 (2750 1700)(3175 1700);
WIRE 16 -1 (2750 1750)(3175 1750);
WIRE 16 -1 (4275 -50)(2750 -50);
FORCEPROP 2 LAST SIG_NAME M_G_CPU0_SB_RSP<0>
J 0
(3384 -41);
DISPLAY 0.680851 (3384 -41);
PAINT WHITE (3384 -41);
WIRE 16 -1 (4275 0)(2750 0);
FORCEPROP 2 LAST SIG_NAME M_G_CPU0_SB_RSP<1>
J 0
(3384 9);
DISPLAY 0.680851 (3384 9);
PAINT WHITE (3384 9);
WIRE 16 -1 (4275 100)(2750 100);
FORCEPROP 2 LAST SIG_NAME M_G_CPU0_SA_RSP<0>
J 0
(3384 109);
DISPLAY 0.680851 (3384 109);
PAINT WHITE (3384 109);
WIRE 16 -1 (4275 150)(2750 150);
FORCEPROP 2 LAST SIG_NAME M_G_CPU0_SA_RSP<1>
J 0
(3384 159);
DISPLAY 0.680851 (3384 159);
PAINT WHITE (3384 159);
WIRE 16 -1 (4275 -150)(2750 -150);
FORCEPROP 2 LAST SIG_NAME M_G_CPU0_ALERT_N
J 0
(3384 -141);
DISPLAY 0.680851 (3384 -141);
PAINT WHITE (3384 -141);
QUIT
